FILE_TYPE = MACRO_DRAWING;
SET COLOR_WIRE YELLOW;
SET COLOR_PROP ORANGE;
SET COLOR_DOT WHITE;
SET COLOR_ARC YELLOW;
SET COLOR_BODY GREEN;
SET COLOR_NOTE PURPLE;
SET PROP_DISPLAY VALUE;
SET PAGE_NUMBER P71;
FORCEADD Q_CAP..1
(-8500 825);
FORCEPROP 1 LAST LOCATION C2262
J 0
(-8450 925);
DISPLAY 0.489362 (-8450 925);
PAINT SKYBLUE (-8450 925);
FORCEPROP 2 LAST $SEC 1
J 0
(-8450 1025);
DISPLAY 0.680851 (-8450 1025);
PAINT MONO (-8450 1025);
DISPLAY INVISIBLE (-8450 1025);
FORCEPROP 2 LAST CDS_SEC 1
J 0
(-8450 1025);
DISPLAY 1.021277 (-8450 1025);
DISPLAY INVISIBLE (-8450 1025);
FORCEPROP 1 LASTPIN (-8500 925) $PN 1
J 0
(-8490 905);
DISPLAY 0.489362 (-8490 905);
FORCEPROP 1 LASTPIN (-8500 725) $PN 2
J 0
(-8490 705);
DISPLAY 0.489362 (-8490 705);
FORCEPROP 1 LAST MATERIAL X6S
J 0
(-8450 725);
DISPLAY 0.489362 (-8450 725);
PAINT SKYBLUE (-8450 725);
FORCEPROP 1 LAST TOLERANCE 20%
J 0
(-8450 775);
DISPLAY 0.489362 (-8450 775);
PAINT SKYBLUE (-8450 775);
FORCEPROP 1 LAST VALUE 22UF
J 0
(-8450 875);
DISPLAY 0.489362 (-8450 875);
PAINT SKYBLUE (-8450 875);
FORCEPROP 1 LAST VOLTAGE 4V
J 0
(-8450 825);
DISPLAY 0.489362 (-8450 825);
PAINT SKYBLUE (-8450 825);
FORCEPROP 1 LAST PACK_TYPE C0402
J 0
(-8450 625);
DISPLAY 0.489362 (-8450 625);
PAINT SKYBLUE (-8450 625);
FORCEPROP 2 LAST CDS_LIB pure_quanta
J 0
(-8500 825);
PAINT MONO (-8500 825);
DISPLAY INVISIBLE (-8500 825);
FORCEPROP 1 LAST PATH I1
J 0
(-8450 975);
DISPLAY 0.978723 (-8450 975);
PAINT WHITE (-8450 975);
DISPLAY INVISIBLE (-8450 975);
FORCEPROP 1 LAST PART_NUMBER CH622KMEB02
J 0
(-8450 675);
DISPLAY 0.489362 (-8450 675);
PAINT SKYBLUE (-8450 675);
DISPLAY INVISIBLE (-8450 675);
FORCEADD UNIVERSAL_POWER..1
(-8525 5175);
FORCEPROP 3 LASTPIN (-8525 5125) SIG_NAME PVDDCR_SOC_P1\g
J 0
(-8515 5135);
DISPLAY 0.659574 (-8515 5135);
PAINT MONO (-8515 5135);
DISPLAY INVISIBLE (-8515 5135);
FORCEPROP 1 LAST HDL_POWER PVDDCR_SOC_P1
J 1
(-8525 5225);
DISPLAY 0.489362 (-8525 5225);
PAINT GREEN (-8525 5225);
FORCEPROP 2 LAST CDS_LIB pure_quanta_power
J 0
(-8525 5175);
DISPLAY INVISIBLE (-8525 5175);
FORCEPROP 1 LAST PATH I10
J 0
(-8475 5200);
DISPLAY 0.872340 (-8475 5200);
PAINT AQUA (-8475 5200);
DISPLAY INVISIBLE (-8475 5200);
FORCEADD Q_CAP..1
(-8050 825);
FORCEPROP 1 LAST LOCATION C2267
J 0
(-8000 925);
DISPLAY 0.489362 (-8000 925);
PAINT SKYBLUE (-8000 925);
FORCEPROP 2 LAST $SEC 1
J 0
(-8000 1025);
DISPLAY 0.680851 (-8000 1025);
PAINT MONO (-8000 1025);
DISPLAY INVISIBLE (-8000 1025);
FORCEPROP 2 LAST CDS_SEC 1
J 0
(-8000 1025);
DISPLAY 1.021277 (-8000 1025);
DISPLAY INVISIBLE (-8000 1025);
FORCEPROP 1 LASTPIN (-8050 925) $PN 1
J 0
(-8040 905);
DISPLAY 0.489362 (-8040 905);
FORCEPROP 1 LASTPIN (-8050 725) $PN 2
J 0
(-8040 705);
DISPLAY 0.489362 (-8040 705);
FORCEPROP 1 LAST MATERIAL X6S
J 0
(-8000 725);
DISPLAY 0.489362 (-8000 725);
PAINT SKYBLUE (-8000 725);
FORCEPROP 1 LAST TOLERANCE 20%
J 0
(-8000 775);
DISPLAY 0.489362 (-8000 775);
PAINT SKYBLUE (-8000 775);
FORCEPROP 1 LAST VALUE 22UF
J 0
(-8000 875);
DISPLAY 0.489362 (-8000 875);
PAINT SKYBLUE (-8000 875);
FORCEPROP 1 LAST VOLTAGE 4V
J 0
(-8000 825);
DISPLAY 0.489362 (-8000 825);
PAINT SKYBLUE (-8000 825);
FORCEPROP 1 LAST PACK_TYPE C0402
J 0
(-8000 625);
DISPLAY 0.489362 (-8000 625);
PAINT SKYBLUE (-8000 625);
FORCEPROP 2 LAST CDS_LIB pure_quanta
J 0
(-8050 825);
PAINT MONO (-8050 825);
DISPLAY INVISIBLE (-8050 825);
FORCEPROP 1 LAST PATH I11
J 0
(-8000 975);
DISPLAY 0.978723 (-8000 975);
PAINT WHITE (-8000 975);
DISPLAY INVISIBLE (-8000 975);
FORCEPROP 1 LAST PART_NUMBER CH622KMEB02
J 0
(-8000 675);
DISPLAY 0.489362 (-8000 675);
PAINT SKYBLUE (-8000 675);
DISPLAY INVISIBLE (-8000 675);
FORCEADD Q_CAP..1
(-7600 825);
FORCEPROP 1 LAST LOCATION C3902
J 0
(-7550 925);
DISPLAY 0.489362 (-7550 925);
PAINT SKYBLUE (-7550 925);
FORCEPROP 2 LAST $SEC 1
J 0
(-7550 1025);
DISPLAY 0.680851 (-7550 1025);
PAINT MONO (-7550 1025);
DISPLAY INVISIBLE (-7550 1025);
FORCEPROP 2 LAST CDS_SEC 1
J 0
(-7550 1025);
DISPLAY 1.021277 (-7550 1025);
DISPLAY INVISIBLE (-7550 1025);
FORCEPROP 1 LASTPIN (-7600 925) $PN 1
J 0
(-7590 905);
DISPLAY 0.489362 (-7590 905);
FORCEPROP 1 LASTPIN (-7600 725) $PN 2
J 0
(-7590 705);
DISPLAY 0.489362 (-7590 705);
FORCEPROP 1 LAST MATERIAL X6S
J 0
(-7550 725);
DISPLAY 0.489362 (-7550 725);
PAINT SKYBLUE (-7550 725);
FORCEPROP 1 LAST TOLERANCE 20%
J 0
(-7550 775);
DISPLAY 0.489362 (-7550 775);
PAINT SKYBLUE (-7550 775);
FORCEPROP 1 LAST VALUE 22UF
J 0
(-7550 875);
DISPLAY 0.489362 (-7550 875);
PAINT SKYBLUE (-7550 875);
FORCEPROP 1 LAST VOLTAGE 4V
J 0
(-7550 825);
DISPLAY 0.489362 (-7550 825);
PAINT SKYBLUE (-7550 825);
FORCEPROP 1 LAST PACK_TYPE C0402
J 0
(-7550 625);
DISPLAY 0.489362 (-7550 625);
PAINT SKYBLUE (-7550 625);
FORCEPROP 2 LAST CDS_LIB pure_quanta
J 0
(-7600 825);
PAINT MONO (-7600 825);
DISPLAY INVISIBLE (-7600 825);
FORCEPROP 1 LAST PATH I12
J 0
(-7550 975);
DISPLAY 0.978723 (-7550 975);
PAINT WHITE (-7550 975);
DISPLAY INVISIBLE (-7550 975);
FORCEPROP 1 LAST PART_NUMBER CH622KMEB02
J 0
(-7550 675);
DISPLAY 0.489362 (-7550 675);
PAINT SKYBLUE (-7550 675);
DISPLAY INVISIBLE (-7550 675);
FORCEADD Q_CAP..1
(-8050 1575);
FORCEPROP 1 LAST LOCATION C2266
J 0
(-8000 1675);
DISPLAY 0.489362 (-8000 1675);
PAINT SKYBLUE (-8000 1675);
FORCEPROP 2 LAST $SEC 1
J 0
(-8000 1775);
DISPLAY 0.680851 (-8000 1775);
PAINT MONO (-8000 1775);
DISPLAY INVISIBLE (-8000 1775);
FORCEPROP 2 LAST CDS_SEC 1
J 0
(-8000 1775);
DISPLAY 1.021277 (-8000 1775);
DISPLAY INVISIBLE (-8000 1775);
FORCEPROP 1 LASTPIN (-8050 1675) $PN 1
J 0
(-8040 1655);
DISPLAY 0.489362 (-8040 1655);
FORCEPROP 1 LASTPIN (-8050 1475) $PN 2
J 0
(-8040 1455);
DISPLAY 0.489362 (-8040 1455);
FORCEPROP 1 LAST MATERIAL X6S
J 0
(-8000 1475);
DISPLAY 0.489362 (-8000 1475);
PAINT SKYBLUE (-8000 1475);
FORCEPROP 1 LAST TOLERANCE 20%
J 0
(-8000 1525);
DISPLAY 0.489362 (-8000 1525);
PAINT SKYBLUE (-8000 1525);
FORCEPROP 1 LAST VALUE 22UF
J 0
(-8000 1625);
DISPLAY 0.489362 (-8000 1625);
PAINT SKYBLUE (-8000 1625);
FORCEPROP 1 LAST VOLTAGE 4V
J 0
(-8000 1575);
DISPLAY 0.489362 (-8000 1575);
PAINT SKYBLUE (-8000 1575);
FORCEPROP 1 LAST PACK_TYPE C0402
J 0
(-8000 1375);
DISPLAY 0.489362 (-8000 1375);
PAINT SKYBLUE (-8000 1375);
FORCEPROP 2 LAST CDS_LIB pure_quanta
J 0
(-8050 1575);
PAINT MONO (-8050 1575);
DISPLAY INVISIBLE (-8050 1575);
FORCEPROP 1 LAST PATH I13
J 0
(-8000 1725);
DISPLAY 0.978723 (-8000 1725);
PAINT WHITE (-8000 1725);
DISPLAY INVISIBLE (-8000 1725);
FORCEPROP 1 LAST PART_NUMBER CH622KMEB02
J 0
(-8000 1425);
DISPLAY 0.489362 (-8000 1425);
PAINT SKYBLUE (-8000 1425);
DISPLAY INVISIBLE (-8000 1425);
FORCEADD Q_CAP..1
(-7600 1575);
FORCEPROP 1 LAST LOCATION C2271
J 0
(-7550 1675);
DISPLAY 0.489362 (-7550 1675);
PAINT SKYBLUE (-7550 1675);
FORCEPROP 2 LAST $SEC 1
J 0
(-7550 1775);
DISPLAY 0.680851 (-7550 1775);
PAINT MONO (-7550 1775);
DISPLAY INVISIBLE (-7550 1775);
FORCEPROP 2 LAST CDS_SEC 1
J 0
(-7550 1775);
DISPLAY 1.021277 (-7550 1775);
DISPLAY INVISIBLE (-7550 1775);
FORCEPROP 1 LASTPIN (-7600 1675) $PN 1
J 0
(-7590 1655);
DISPLAY 0.489362 (-7590 1655);
FORCEPROP 1 LASTPIN (-7600 1475) $PN 2
J 0
(-7590 1455);
DISPLAY 0.489362 (-7590 1455);
FORCEPROP 1 LAST MATERIAL X6S
J 0
(-7550 1475);
DISPLAY 0.489362 (-7550 1475);
PAINT SKYBLUE (-7550 1475);
FORCEPROP 1 LAST TOLERANCE 20%
J 0
(-7550 1525);
DISPLAY 0.489362 (-7550 1525);
PAINT SKYBLUE (-7550 1525);
FORCEPROP 1 LAST VALUE 22UF
J 0
(-7550 1625);
DISPLAY 0.489362 (-7550 1625);
PAINT SKYBLUE (-7550 1625);
FORCEPROP 1 LAST VOLTAGE 4V
J 0
(-7550 1575);
DISPLAY 0.489362 (-7550 1575);
PAINT SKYBLUE (-7550 1575);
FORCEPROP 1 LAST PACK_TYPE C0402
J 0
(-7550 1375);
DISPLAY 0.489362 (-7550 1375);
PAINT SKYBLUE (-7550 1375);
FORCEPROP 2 LAST CDS_LIB pure_quanta
J 0
(-7600 1575);
PAINT MONO (-7600 1575);
DISPLAY INVISIBLE (-7600 1575);
FORCEPROP 1 LAST PATH I14
J 0
(-7550 1725);
DISPLAY 0.978723 (-7550 1725);
PAINT WHITE (-7550 1725);
DISPLAY INVISIBLE (-7550 1725);
FORCEPROP 1 LAST PART_NUMBER CH622KMEB02
J 0
(-7550 1425);
DISPLAY 0.489362 (-7550 1425);
PAINT SKYBLUE (-7550 1425);
DISPLAY INVISIBLE (-7550 1425);
FORCEADD Q_CAP..1
(-7150 825);
FORCEPROP 1 LAST LOCATION C3903
J 0
(-7100 925);
DISPLAY 0.489362 (-7100 925);
PAINT SKYBLUE (-7100 925);
FORCEPROP 2 LAST $SEC 1
J 0
(-7100 1025);
DISPLAY 0.680851 (-7100 1025);
PAINT MONO (-7100 1025);
DISPLAY INVISIBLE (-7100 1025);
FORCEPROP 2 LAST CDS_SEC 1
J 0
(-7100 1025);
DISPLAY 1.021277 (-7100 1025);
DISPLAY INVISIBLE (-7100 1025);
FORCEPROP 1 LASTPIN (-7150 925) $PN 1
J 0
(-7140 905);
DISPLAY 0.489362 (-7140 905);
FORCEPROP 1 LASTPIN (-7150 725) $PN 2
J 0
(-7140 705);
DISPLAY 0.489362 (-7140 705);
FORCEPROP 1 LAST MATERIAL X6S
J 0
(-7100 725);
DISPLAY 0.489362 (-7100 725);
PAINT SKYBLUE (-7100 725);
FORCEPROP 1 LAST TOLERANCE 20%
J 0
(-7100 775);
DISPLAY 0.489362 (-7100 775);
PAINT SKYBLUE (-7100 775);
FORCEPROP 1 LAST VALUE 22UF
J 0
(-7100 875);
DISPLAY 0.489362 (-7100 875);
PAINT SKYBLUE (-7100 875);
FORCEPROP 1 LAST VOLTAGE 4V
J 0
(-7100 825);
DISPLAY 0.489362 (-7100 825);
PAINT SKYBLUE (-7100 825);
FORCEPROP 1 LAST PACK_TYPE C0402
J 0
(-7100 625);
DISPLAY 0.489362 (-7100 625);
PAINT SKYBLUE (-7100 625);
FORCEPROP 2 LAST CDS_LIB pure_quanta
J 0
(-7150 825);
PAINT MONO (-7150 825);
DISPLAY INVISIBLE (-7150 825);
FORCEPROP 1 LAST PATH I15
J 0
(-7100 975);
DISPLAY 0.978723 (-7100 975);
PAINT WHITE (-7100 975);
DISPLAY INVISIBLE (-7100 975);
FORCEPROP 1 LAST PART_NUMBER CH622KMEB02
J 0
(-7100 675);
DISPLAY 0.489362 (-7100 675);
PAINT SKYBLUE (-7100 675);
DISPLAY INVISIBLE (-7100 675);
FORCEADD Q_CAP..1
(-6700 825);
FORCEPROP 1 LAST LOCATION C3904
J 0
(-6650 925);
DISPLAY 0.489362 (-6650 925);
PAINT SKYBLUE (-6650 925);
FORCEPROP 2 LAST $SEC 1
J 0
(-6650 1025);
DISPLAY 0.680851 (-6650 1025);
PAINT MONO (-6650 1025);
DISPLAY INVISIBLE (-6650 1025);
FORCEPROP 2 LAST CDS_SEC 1
J 0
(-6650 1025);
DISPLAY 1.021277 (-6650 1025);
DISPLAY INVISIBLE (-6650 1025);
FORCEPROP 1 LASTPIN (-6700 925) $PN 1
J 0
(-6690 905);
DISPLAY 0.489362 (-6690 905);
FORCEPROP 1 LASTPIN (-6700 725) $PN 2
J 0
(-6690 705);
DISPLAY 0.489362 (-6690 705);
FORCEPROP 1 LAST MATERIAL X6S
J 0
(-6650 725);
DISPLAY 0.489362 (-6650 725);
PAINT SKYBLUE (-6650 725);
FORCEPROP 1 LAST TOLERANCE 20%
J 0
(-6650 775);
DISPLAY 0.489362 (-6650 775);
PAINT SKYBLUE (-6650 775);
FORCEPROP 1 LAST VALUE 22UF
J 0
(-6650 875);
DISPLAY 0.489362 (-6650 875);
PAINT SKYBLUE (-6650 875);
FORCEPROP 1 LAST VOLTAGE 4V
J 0
(-6650 825);
DISPLAY 0.489362 (-6650 825);
PAINT SKYBLUE (-6650 825);
FORCEPROP 1 LAST PACK_TYPE C0402
J 0
(-6650 625);
DISPLAY 0.489362 (-6650 625);
PAINT SKYBLUE (-6650 625);
FORCEPROP 2 LAST CDS_LIB pure_quanta
J 0
(-6700 825);
PAINT MONO (-6700 825);
DISPLAY INVISIBLE (-6700 825);
FORCEPROP 1 LAST PATH I16
J 0
(-6650 975);
DISPLAY 0.978723 (-6650 975);
PAINT WHITE (-6650 975);
DISPLAY INVISIBLE (-6650 975);
FORCEPROP 1 LAST PART_NUMBER CH622KMEB02
J 0
(-6650 675);
DISPLAY 0.489362 (-6650 675);
PAINT SKYBLUE (-6650 675);
DISPLAY INVISIBLE (-6650 675);
FORCEADD UNIVERSAL_GND..1
(-6250 450);
FORCEPROP 3 LASTPIN (-6250 500) SIG_NAME GND\g
J 0
(-6240 510);
DISPLAY 0.659574 (-6240 510);
PAINT MONO (-6240 510);
DISPLAY INVISIBLE (-6240 510);
FORCEPROP 2 LAST CDS_LIB pure_quanta_power
J 0
(-6250 450);
PAINT MONO (-6250 450);
DISPLAY INVISIBLE (-6250 450);
FORCEPROP 1 LAST HDL_POWER GND
J 1
(-6225 375);
DISPLAY 0.872340 (-6225 375);
PAINT GREEN (-6225 375);
DISPLAY INVISIBLE (-6225 375);
FORCEPROP 1 LAST PATH I17
J 0
(-6175 450);
DISPLAY 0.872340 (-6175 450);
PAINT AQUA (-6175 450);
DISPLAY INVISIBLE (-6175 450);
FORCEADD Q_CAP..1
(-6250 825);
FORCEPROP 1 LAST LOCATION C3905
J 0
(-6200 925);
DISPLAY 0.489362 (-6200 925);
PAINT SKYBLUE (-6200 925);
FORCEPROP 2 LAST $SEC 1
J 0
(-6200 1025);
DISPLAY 0.680851 (-6200 1025);
PAINT MONO (-6200 1025);
DISPLAY INVISIBLE (-6200 1025);
FORCEPROP 2 LAST CDS_SEC 1
J 0
(-6200 1025);
DISPLAY 1.021277 (-6200 1025);
DISPLAY INVISIBLE (-6200 1025);
FORCEPROP 1 LASTPIN (-6250 925) $PN 1
J 0
(-6240 905);
DISPLAY 0.489362 (-6240 905);
FORCEPROP 1 LASTPIN (-6250 725) $PN 2
J 0
(-6240 705);
DISPLAY 0.489362 (-6240 705);
FORCEPROP 1 LAST MATERIAL X6S
J 0
(-6200 725);
DISPLAY 0.489362 (-6200 725);
PAINT SKYBLUE (-6200 725);
FORCEPROP 1 LAST TOLERANCE 20%
J 0
(-6200 775);
DISPLAY 0.489362 (-6200 775);
PAINT SKYBLUE (-6200 775);
FORCEPROP 1 LAST VALUE 22UF
J 0
(-6200 875);
DISPLAY 0.489362 (-6200 875);
PAINT SKYBLUE (-6200 875);
FORCEPROP 1 LAST VOLTAGE 4V
J 0
(-6200 825);
DISPLAY 0.489362 (-6200 825);
PAINT SKYBLUE (-6200 825);
FORCEPROP 1 LAST PACK_TYPE C0402
J 0
(-6200 625);
DISPLAY 0.489362 (-6200 625);
PAINT SKYBLUE (-6200 625);
FORCEPROP 2 LAST CDS_LIB pure_quanta
J 0
(-6250 825);
PAINT MONO (-6250 825);
DISPLAY INVISIBLE (-6250 825);
FORCEPROP 1 LAST PATH I18
J 0
(-6200 975);
DISPLAY 0.978723 (-6200 975);
PAINT WHITE (-6200 975);
DISPLAY INVISIBLE (-6200 975);
FORCEPROP 1 LAST PART_NUMBER CH622KMEB02
J 0
(-6200 675);
DISPLAY 0.489362 (-6200 675);
PAINT SKYBLUE (-6200 675);
DISPLAY INVISIBLE (-6200 675);
FORCEADD Q_CAP..1
(-7150 1575);
FORCEPROP 1 LAST LOCATION C2275
J 0
(-7100 1675);
DISPLAY 0.489362 (-7100 1675);
PAINT SKYBLUE (-7100 1675);
FORCEPROP 2 LAST $SEC 1
J 0
(-7100 1775);
DISPLAY 0.680851 (-7100 1775);
PAINT MONO (-7100 1775);
DISPLAY INVISIBLE (-7100 1775);
FORCEPROP 2 LAST CDS_SEC 1
J 0
(-7100 1775);
DISPLAY 1.021277 (-7100 1775);
DISPLAY INVISIBLE (-7100 1775);
FORCEPROP 1 LASTPIN (-7150 1675) $PN 1
J 0
(-7140 1655);
DISPLAY 0.489362 (-7140 1655);
FORCEPROP 1 LASTPIN (-7150 1475) $PN 2
J 0
(-7140 1455);
DISPLAY 0.489362 (-7140 1455);
FORCEPROP 1 LAST MATERIAL X6S
J 0
(-7100 1475);
DISPLAY 0.489362 (-7100 1475);
PAINT SKYBLUE (-7100 1475);
FORCEPROP 1 LAST TOLERANCE 20%
J 0
(-7100 1525);
DISPLAY 0.489362 (-7100 1525);
PAINT SKYBLUE (-7100 1525);
FORCEPROP 1 LAST VALUE 22UF
J 0
(-7100 1625);
DISPLAY 0.489362 (-7100 1625);
PAINT SKYBLUE (-7100 1625);
FORCEPROP 1 LAST VOLTAGE 4V
J 0
(-7100 1575);
DISPLAY 0.489362 (-7100 1575);
PAINT SKYBLUE (-7100 1575);
FORCEPROP 1 LAST PACK_TYPE C0402
J 0
(-7100 1375);
DISPLAY 0.489362 (-7100 1375);
PAINT SKYBLUE (-7100 1375);
FORCEPROP 2 LAST CDS_LIB pure_quanta
J 0
(-7150 1575);
PAINT MONO (-7150 1575);
DISPLAY INVISIBLE (-7150 1575);
FORCEPROP 1 LAST PATH I19
J 0
(-7100 1725);
DISPLAY 0.978723 (-7100 1725);
PAINT WHITE (-7100 1725);
DISPLAY INVISIBLE (-7100 1725);
FORCEPROP 1 LAST PART_NUMBER CH622KMEB02
J 0
(-7100 1425);
DISPLAY 0.489362 (-7100 1425);
PAINT SKYBLUE (-7100 1425);
DISPLAY INVISIBLE (-7100 1425);
FORCEADD UNIVERSAL_POWER..1
(-8500 1100);
FORCEPROP 3 LASTPIN (-8500 1050) SIG_NAME PVDD11_S3_P1\g
J 0
(-8490 1060);
DISPLAY 0.659574 (-8490 1060);
PAINT MONO (-8490 1060);
DISPLAY INVISIBLE (-8490 1060);
FORCEPROP 1 LAST HDL_POWER PVDD11_S3_P1
J 1
(-8500 1150);
DISPLAY 0.489362 (-8500 1150);
PAINT GREEN (-8500 1150);
FORCEPROP 2 LAST CDS_LIB pure_quanta_power
J 0
(-8500 1100);
DISPLAY INVISIBLE (-8500 1100);
FORCEPROP 1 LAST PATH I2
J 0
(-8450 1125);
DISPLAY 0.872340 (-8450 1125);
PAINT AQUA (-8450 1125);
DISPLAY INVISIBLE (-8450 1125);
FORCEADD Q_CAP..1
(-6700 1575);
FORCEPROP 1 LAST LOCATION C2279
J 0
(-6650 1675);
DISPLAY 0.489362 (-6650 1675);
PAINT SKYBLUE (-6650 1675);
FORCEPROP 2 LAST $SEC 1
J 0
(-6650 1775);
DISPLAY 0.680851 (-6650 1775);
PAINT MONO (-6650 1775);
DISPLAY INVISIBLE (-6650 1775);
FORCEPROP 2 LAST CDS_SEC 1
J 0
(-6650 1775);
DISPLAY 1.021277 (-6650 1775);
DISPLAY INVISIBLE (-6650 1775);
FORCEPROP 1 LASTPIN (-6700 1675) $PN 1
J 0
(-6690 1655);
DISPLAY 0.489362 (-6690 1655);
FORCEPROP 1 LASTPIN (-6700 1475) $PN 2
J 0
(-6690 1455);
DISPLAY 0.489362 (-6690 1455);
FORCEPROP 1 LAST MATERIAL X6S
J 0
(-6650 1475);
DISPLAY 0.489362 (-6650 1475);
PAINT SKYBLUE (-6650 1475);
FORCEPROP 1 LAST TOLERANCE 20%
J 0
(-6650 1525);
DISPLAY 0.489362 (-6650 1525);
PAINT SKYBLUE (-6650 1525);
FORCEPROP 1 LAST VALUE 22UF
J 0
(-6650 1625);
DISPLAY 0.489362 (-6650 1625);
PAINT SKYBLUE (-6650 1625);
FORCEPROP 1 LAST VOLTAGE 4V
J 0
(-6650 1575);
DISPLAY 0.489362 (-6650 1575);
PAINT SKYBLUE (-6650 1575);
FORCEPROP 1 LAST PACK_TYPE C0402
J 0
(-6650 1375);
DISPLAY 0.489362 (-6650 1375);
PAINT SKYBLUE (-6650 1375);
FORCEPROP 2 LAST CDS_LIB pure_quanta
J 0
(-6700 1575);
PAINT MONO (-6700 1575);
DISPLAY INVISIBLE (-6700 1575);
FORCEPROP 1 LAST PATH I20
J 0
(-6650 1725);
DISPLAY 0.978723 (-6650 1725);
PAINT WHITE (-6650 1725);
DISPLAY INVISIBLE (-6650 1725);
FORCEPROP 1 LAST PART_NUMBER CH622KMEB02
J 0
(-6650 1425);
DISPLAY 0.489362 (-6650 1425);
PAINT SKYBLUE (-6650 1425);
DISPLAY INVISIBLE (-6650 1425);
FORCEADD Q_CAP..1
(-6250 1575);
FORCEPROP 1 LAST LOCATION C2282
J 0
(-6200 1675);
DISPLAY 0.489362 (-6200 1675);
PAINT SKYBLUE (-6200 1675);
FORCEPROP 2 LAST $SEC 1
J 0
(-6200 1775);
DISPLAY 0.680851 (-6200 1775);
PAINT MONO (-6200 1775);
DISPLAY INVISIBLE (-6200 1775);
FORCEPROP 2 LAST CDS_SEC 1
J 0
(-6200 1775);
DISPLAY 1.021277 (-6200 1775);
DISPLAY INVISIBLE (-6200 1775);
FORCEPROP 1 LASTPIN (-6250 1675) $PN 1
J 0
(-6240 1655);
DISPLAY 0.489362 (-6240 1655);
FORCEPROP 1 LASTPIN (-6250 1475) $PN 2
J 0
(-6240 1455);
DISPLAY 0.489362 (-6240 1455);
FORCEPROP 1 LAST MATERIAL X6S
J 0
(-6200 1475);
DISPLAY 0.489362 (-6200 1475);
PAINT SKYBLUE (-6200 1475);
FORCEPROP 1 LAST TOLERANCE 20%
J 0
(-6200 1525);
DISPLAY 0.489362 (-6200 1525);
PAINT SKYBLUE (-6200 1525);
FORCEPROP 1 LAST VALUE 22UF
J 0
(-6200 1625);
DISPLAY 0.489362 (-6200 1625);
PAINT SKYBLUE (-6200 1625);
FORCEPROP 1 LAST VOLTAGE 4V
J 0
(-6200 1575);
DISPLAY 0.489362 (-6200 1575);
PAINT SKYBLUE (-6200 1575);
FORCEPROP 1 LAST PACK_TYPE C0402
J 0
(-6200 1375);
DISPLAY 0.489362 (-6200 1375);
PAINT SKYBLUE (-6200 1375);
FORCEPROP 2 LAST CDS_LIB pure_quanta
J 0
(-6250 1575);
PAINT MONO (-6250 1575);
DISPLAY INVISIBLE (-6250 1575);
FORCEPROP 1 LAST PATH I21
J 0
(-6200 1725);
DISPLAY 0.978723 (-6200 1725);
PAINT WHITE (-6200 1725);
DISPLAY INVISIBLE (-6200 1725);
FORCEPROP 1 LAST PART_NUMBER CH622KMEB02
J 0
(-6200 1425);
DISPLAY 0.489362 (-6200 1425);
PAINT SKYBLUE (-6200 1425);
DISPLAY INVISIBLE (-6200 1425);
FORCEADD UNIVERSAL_GND..1
(-8075 3025);
FORCEPROP 3 LASTPIN (-8075 3075) SIG_NAME GND\g
J 0
(-8065 3085);
DISPLAY 0.659574 (-8065 3085);
PAINT MONO (-8065 3085);
DISPLAY INVISIBLE (-8065 3085);
FORCEPROP 2 LAST CDS_LIB pure_quanta_power
J 0
(-8075 3025);
DISPLAY INVISIBLE (-8075 3025);
FORCEPROP 1 LAST HDL_POWER GND
J 1
(-8050 2950);
DISPLAY 0.872340 (-8050 2950);
PAINT GREEN (-8050 2950);
DISPLAY INVISIBLE (-8050 2950);
FORCEPROP 1 LAST PATH I22
J 0
(-8000 3025);
DISPLAY 0.872340 (-8000 3025);
PAINT AQUA (-8000 3025);
DISPLAY INVISIBLE (-8000 3025);
FORCEADD Q_CAP..1
(-8075 3375);
FORCEPROP 1 LAST LOCATION C3901
J 0
(-8025 3475);
DISPLAY 0.489362 (-8025 3475);
PAINT SKYBLUE (-8025 3475);
FORCEPROP 2 LAST $SEC 1
J 0
(-8025 3575);
DISPLAY 0.680851 (-8025 3575);
PAINT MONO (-8025 3575);
DISPLAY INVISIBLE (-8025 3575);
FORCEPROP 2 LAST CDS_SEC 1
J 0
(-8025 3575);
DISPLAY 1.021277 (-8025 3575);
DISPLAY INVISIBLE (-8025 3575);
FORCEPROP 1 LASTPIN (-8075 3475) $PN 1
J 0
(-8065 3455);
DISPLAY 0.489362 (-8065 3455);
FORCEPROP 1 LASTPIN (-8075 3275) $PN 2
J 0
(-8065 3255);
DISPLAY 0.489362 (-8065 3255);
FORCEPROP 1 LAST MATERIAL X6S
J 0
(-8025 3275);
DISPLAY 0.489362 (-8025 3275);
PAINT SKYBLUE (-8025 3275);
FORCEPROP 1 LAST TOLERANCE 20%
J 0
(-8025 3325);
DISPLAY 0.489362 (-8025 3325);
PAINT SKYBLUE (-8025 3325);
FORCEPROP 1 LAST VALUE 22UF
J 0
(-8025 3425);
DISPLAY 0.489362 (-8025 3425);
PAINT SKYBLUE (-8025 3425);
FORCEPROP 1 LAST VOLTAGE 4V
J 0
(-8025 3375);
DISPLAY 0.489362 (-8025 3375);
PAINT SKYBLUE (-8025 3375);
FORCEPROP 1 LAST PACK_TYPE C0402
J 0
(-8025 3175);
DISPLAY 0.489362 (-8025 3175);
PAINT SKYBLUE (-8025 3175);
FORCEPROP 2 LAST CDS_LIB pure_quanta
J 0
(-8075 3375);
PAINT MONO (-8075 3375);
DISPLAY INVISIBLE (-8075 3375);
FORCEPROP 1 LAST PATH I23
J 0
(-8025 3525);
DISPLAY 0.978723 (-8025 3525);
PAINT WHITE (-8025 3525);
DISPLAY INVISIBLE (-8025 3525);
FORCEPROP 1 LAST PART_NUMBER CH622KMEB02
J 0
(-8025 3225);
DISPLAY 0.489362 (-8025 3225);
PAINT SKYBLUE (-8025 3225);
DISPLAY INVISIBLE (-8025 3225);
FORCEADD Q_CAP..1
(-5800 1575);
FORCEPROP 1 LAST LOCATION C2285
J 0
(-5750 1675);
DISPLAY 0.489362 (-5750 1675);
PAINT SKYBLUE (-5750 1675);
FORCEPROP 2 LAST $SEC 1
J 0
(-5750 1775);
DISPLAY 0.680851 (-5750 1775);
PAINT MONO (-5750 1775);
DISPLAY INVISIBLE (-5750 1775);
FORCEPROP 2 LAST CDS_SEC 1
J 0
(-5750 1775);
DISPLAY 1.021277 (-5750 1775);
DISPLAY INVISIBLE (-5750 1775);
FORCEPROP 1 LASTPIN (-5800 1675) $PN 1
J 0
(-5790 1655);
DISPLAY 0.489362 (-5790 1655);
FORCEPROP 1 LASTPIN (-5800 1475) $PN 2
J 0
(-5790 1455);
DISPLAY 0.489362 (-5790 1455);
FORCEPROP 1 LAST MATERIAL X6S
J 0
(-5750 1475);
DISPLAY 0.489362 (-5750 1475);
PAINT SKYBLUE (-5750 1475);
FORCEPROP 1 LAST TOLERANCE 20%
J 0
(-5750 1525);
DISPLAY 0.489362 (-5750 1525);
PAINT SKYBLUE (-5750 1525);
FORCEPROP 1 LAST VALUE 22UF
J 0
(-5750 1625);
DISPLAY 0.489362 (-5750 1625);
PAINT SKYBLUE (-5750 1625);
FORCEPROP 1 LAST VOLTAGE 4V
J 0
(-5750 1575);
DISPLAY 0.489362 (-5750 1575);
PAINT SKYBLUE (-5750 1575);
FORCEPROP 1 LAST PACK_TYPE C0402
J 0
(-5750 1375);
DISPLAY 0.489362 (-5750 1375);
PAINT SKYBLUE (-5750 1375);
FORCEPROP 2 LAST CDS_LIB pure_quanta
J 0
(-5800 1575);
PAINT MONO (-5800 1575);
DISPLAY INVISIBLE (-5800 1575);
FORCEPROP 1 LAST PATH I24
J 0
(-5750 1725);
DISPLAY 0.978723 (-5750 1725);
PAINT WHITE (-5750 1725);
DISPLAY INVISIBLE (-5750 1725);
FORCEPROP 1 LAST PART_NUMBER CH622KMEB02
J 0
(-5750 1425);
DISPLAY 0.489362 (-5750 1425);
PAINT SKYBLUE (-5750 1425);
DISPLAY INVISIBLE (-5750 1425);
FORCEADD Q_CAP..1
(-5350 1575);
FORCEPROP 1 LAST LOCATION C2287
J 0
(-5300 1675);
DISPLAY 0.489362 (-5300 1675);
PAINT SKYBLUE (-5300 1675);
FORCEPROP 2 LAST $SEC 1
J 0
(-5300 1775);
DISPLAY 0.680851 (-5300 1775);
PAINT MONO (-5300 1775);
DISPLAY INVISIBLE (-5300 1775);
FORCEPROP 2 LAST CDS_SEC 1
J 0
(-5300 1775);
DISPLAY 1.021277 (-5300 1775);
DISPLAY INVISIBLE (-5300 1775);
FORCEPROP 1 LASTPIN (-5350 1675) $PN 1
J 0
(-5340 1655);
DISPLAY 0.489362 (-5340 1655);
FORCEPROP 1 LASTPIN (-5350 1475) $PN 2
J 0
(-5340 1455);
DISPLAY 0.489362 (-5340 1455);
FORCEPROP 1 LAST MATERIAL X6S
J 0
(-5300 1475);
DISPLAY 0.489362 (-5300 1475);
PAINT SKYBLUE (-5300 1475);
FORCEPROP 1 LAST TOLERANCE 20%
J 0
(-5300 1525);
DISPLAY 0.489362 (-5300 1525);
PAINT SKYBLUE (-5300 1525);
FORCEPROP 1 LAST VALUE 22UF
J 0
(-5300 1625);
DISPLAY 0.489362 (-5300 1625);
PAINT SKYBLUE (-5300 1625);
FORCEPROP 1 LAST VOLTAGE 4V
J 0
(-5300 1575);
DISPLAY 0.489362 (-5300 1575);
PAINT SKYBLUE (-5300 1575);
FORCEPROP 1 LAST PACK_TYPE C0402
J 0
(-5300 1375);
DISPLAY 0.489362 (-5300 1375);
PAINT SKYBLUE (-5300 1375);
FORCEPROP 2 LAST CDS_LIB pure_quanta
J 0
(-5350 1575);
PAINT MONO (-5350 1575);
DISPLAY INVISIBLE (-5350 1575);
FORCEPROP 1 LAST PATH I25
J 0
(-5300 1725);
DISPLAY 0.978723 (-5300 1725);
PAINT WHITE (-5300 1725);
DISPLAY INVISIBLE (-5300 1725);
FORCEPROP 1 LAST PART_NUMBER CH622KMEB02
J 0
(-5300 1425);
DISPLAY 0.489362 (-5300 1425);
PAINT SKYBLUE (-5300 1425);
DISPLAY INVISIBLE (-5300 1425);
FORCEADD Q_CAP..1
(-4900 1575);
FORCEPROP 1 LAST LOCATION C2289
J 0
(-4850 1675);
DISPLAY 0.489362 (-4850 1675);
PAINT SKYBLUE (-4850 1675);
FORCEPROP 2 LAST $SEC 1
J 0
(-4850 1775);
DISPLAY 0.680851 (-4850 1775);
PAINT MONO (-4850 1775);
DISPLAY INVISIBLE (-4850 1775);
FORCEPROP 2 LAST CDS_SEC 1
J 0
(-4850 1775);
DISPLAY 1.021277 (-4850 1775);
DISPLAY INVISIBLE (-4850 1775);
FORCEPROP 1 LASTPIN (-4900 1675) $PN 1
J 0
(-4890 1655);
DISPLAY 0.489362 (-4890 1655);
FORCEPROP 1 LASTPIN (-4900 1475) $PN 2
J 0
(-4890 1455);
DISPLAY 0.489362 (-4890 1455);
FORCEPROP 1 LAST MATERIAL X6S
J 0
(-4850 1475);
DISPLAY 0.489362 (-4850 1475);
PAINT SKYBLUE (-4850 1475);
FORCEPROP 1 LAST TOLERANCE 20%
J 0
(-4850 1525);
DISPLAY 0.489362 (-4850 1525);
PAINT SKYBLUE (-4850 1525);
FORCEPROP 1 LAST VALUE 22UF
J 0
(-4850 1625);
DISPLAY 0.489362 (-4850 1625);
PAINT SKYBLUE (-4850 1625);
FORCEPROP 1 LAST VOLTAGE 4V
J 0
(-4850 1575);
DISPLAY 0.489362 (-4850 1575);
PAINT SKYBLUE (-4850 1575);
FORCEPROP 1 LAST PACK_TYPE C0402
J 0
(-4850 1375);
DISPLAY 0.489362 (-4850 1375);
PAINT SKYBLUE (-4850 1375);
FORCEPROP 2 LAST CDS_LIB pure_quanta
J 0
(-4900 1575);
PAINT MONO (-4900 1575);
DISPLAY INVISIBLE (-4900 1575);
FORCEPROP 1 LAST PATH I26
J 0
(-4850 1725);
DISPLAY 0.978723 (-4850 1725);
PAINT WHITE (-4850 1725);
DISPLAY INVISIBLE (-4850 1725);
FORCEPROP 1 LAST PART_NUMBER CH622KMEB02
J 0
(-4850 1425);
DISPLAY 0.489362 (-4850 1425);
PAINT SKYBLUE (-4850 1425);
DISPLAY INVISIBLE (-4850 1425);
FORCEADD UNIVERSAL_GND..1
(-4500 1200);
FORCEPROP 3 LASTPIN (-4500 1250) SIG_NAME GND\g
J 0
(-4490 1260);
DISPLAY 0.659574 (-4490 1260);
PAINT MONO (-4490 1260);
DISPLAY INVISIBLE (-4490 1260);
FORCEPROP 2 LAST CDS_LIB pure_quanta_power
J 0
(-4500 1200);
PAINT MONO (-4500 1200);
DISPLAY INVISIBLE (-4500 1200);
FORCEPROP 1 LAST HDL_POWER GND
J 1
(-4475 1125);
DISPLAY 0.872340 (-4475 1125);
PAINT GREEN (-4475 1125);
DISPLAY INVISIBLE (-4475 1125);
FORCEPROP 1 LAST PATH I27
J 0
(-4425 1200);
DISPLAY 0.872340 (-4425 1200);
PAINT AQUA (-4425 1200);
DISPLAY INVISIBLE (-4425 1200);
FORCEADD Q_CAP..1
(-4500 1575);
FORCEPROP 1 LAST LOCATION C2291
J 0
(-4450 1675);
DISPLAY 0.489362 (-4450 1675);
PAINT SKYBLUE (-4450 1675);
FORCEPROP 2 LAST $SEC 1
J 0
(-4450 1775);
DISPLAY 0.680851 (-4450 1775);
PAINT MONO (-4450 1775);
DISPLAY INVISIBLE (-4450 1775);
FORCEPROP 2 LAST CDS_SEC 1
J 0
(-4450 1775);
DISPLAY 1.021277 (-4450 1775);
DISPLAY INVISIBLE (-4450 1775);
FORCEPROP 1 LASTPIN (-4500 1675) $PN 1
J 0
(-4490 1655);
DISPLAY 0.489362 (-4490 1655);
FORCEPROP 1 LASTPIN (-4500 1475) $PN 2
J 0
(-4490 1455);
DISPLAY 0.489362 (-4490 1455);
FORCEPROP 1 LAST MATERIAL X6S
J 0
(-4450 1475);
DISPLAY 0.489362 (-4450 1475);
PAINT SKYBLUE (-4450 1475);
FORCEPROP 1 LAST TOLERANCE 20%
J 0
(-4450 1525);
DISPLAY 0.489362 (-4450 1525);
PAINT SKYBLUE (-4450 1525);
FORCEPROP 1 LAST VALUE 22UF
J 0
(-4450 1625);
DISPLAY 0.489362 (-4450 1625);
PAINT SKYBLUE (-4450 1625);
FORCEPROP 1 LAST VOLTAGE 4V
J 0
(-4450 1575);
DISPLAY 0.489362 (-4450 1575);
PAINT SKYBLUE (-4450 1575);
FORCEPROP 1 LAST PACK_TYPE C0402
J 0
(-4450 1375);
DISPLAY 0.489362 (-4450 1375);
PAINT SKYBLUE (-4450 1375);
FORCEPROP 2 LAST CDS_LIB pure_quanta
J 0
(-4500 1575);
PAINT MONO (-4500 1575);
DISPLAY INVISIBLE (-4500 1575);
FORCEPROP 1 LAST PATH I28
J 0
(-4450 1725);
DISPLAY 0.978723 (-4450 1725);
PAINT WHITE (-4450 1725);
DISPLAY INVISIBLE (-4450 1725);
FORCEPROP 1 LAST PART_NUMBER CH622KMEB02
J 0
(-4450 1425);
DISPLAY 0.489362 (-4450 1425);
PAINT SKYBLUE (-4450 1425);
DISPLAY INVISIBLE (-4450 1425);
FORCEADD UNIVERSAL_GND..1
(-4525 3725);
FORCEPROP 3 LASTPIN (-4525 3775) SIG_NAME GND\g
J 0
(-4515 3785);
DISPLAY 0.659574 (-4515 3785);
PAINT MONO (-4515 3785);
DISPLAY INVISIBLE (-4515 3785);
FORCEPROP 2 LAST CDS_LIB pure_quanta_power
J 0
(-4525 3725);
PAINT MONO (-4525 3725);
DISPLAY INVISIBLE (-4525 3725);
FORCEPROP 1 LAST HDL_POWER GND
J 1
(-4500 3650);
DISPLAY 0.872340 (-4500 3650);
PAINT GREEN (-4500 3650);
DISPLAY INVISIBLE (-4500 3650);
FORCEPROP 1 LAST PATH I29
J 0
(-4450 3725);
DISPLAY 0.872340 (-4450 3725);
PAINT AQUA (-4450 3725);
DISPLAY INVISIBLE (-4450 3725);
FORCEADD Q_CAP..1
(-8500 1575);
FORCEPROP 1 LAST LOCATION C2261
J 0
(-8450 1675);
DISPLAY 0.489362 (-8450 1675);
PAINT SKYBLUE (-8450 1675);
FORCEPROP 2 LAST $SEC 1
J 0
(-8450 1775);
DISPLAY 0.680851 (-8450 1775);
PAINT MONO (-8450 1775);
DISPLAY INVISIBLE (-8450 1775);
FORCEPROP 2 LAST CDS_SEC 1
J 0
(-8450 1775);
DISPLAY 1.021277 (-8450 1775);
DISPLAY INVISIBLE (-8450 1775);
FORCEPROP 1 LASTPIN (-8500 1675) $PN 1
J 0
(-8490 1655);
DISPLAY 0.489362 (-8490 1655);
FORCEPROP 1 LASTPIN (-8500 1475) $PN 2
J 0
(-8490 1455);
DISPLAY 0.489362 (-8490 1455);
FORCEPROP 1 LAST MATERIAL X6S
J 0
(-8450 1475);
DISPLAY 0.489362 (-8450 1475);
PAINT SKYBLUE (-8450 1475);
FORCEPROP 1 LAST TOLERANCE 20%
J 0
(-8450 1525);
DISPLAY 0.489362 (-8450 1525);
PAINT SKYBLUE (-8450 1525);
FORCEPROP 1 LAST VALUE 22UF
J 0
(-8450 1625);
DISPLAY 0.489362 (-8450 1625);
PAINT SKYBLUE (-8450 1625);
FORCEPROP 1 LAST VOLTAGE 4V
J 0
(-8450 1575);
DISPLAY 0.489362 (-8450 1575);
PAINT SKYBLUE (-8450 1575);
FORCEPROP 1 LAST PACK_TYPE C0402
J 0
(-8450 1375);
DISPLAY 0.489362 (-8450 1375);
PAINT SKYBLUE (-8450 1375);
FORCEPROP 2 LAST CDS_LIB pure_quanta
J 0
(-8500 1575);
PAINT MONO (-8500 1575);
DISPLAY INVISIBLE (-8500 1575);
FORCEPROP 1 LAST PATH I3
J 0
(-8450 1725);
DISPLAY 0.978723 (-8450 1725);
PAINT WHITE (-8450 1725);
DISPLAY INVISIBLE (-8450 1725);
FORCEPROP 1 LAST PART_NUMBER CH622KMEB02
J 0
(-8450 1425);
DISPLAY 0.489362 (-8450 1425);
PAINT SKYBLUE (-8450 1425);
DISPLAY INVISIBLE (-8450 1425);
FORCEADD Q_CAP..1
(-8075 4100);
FORCEPROP 1 LAST LOCATION C2264
J 0
(-8025 4200);
DISPLAY 0.489362 (-8025 4200);
PAINT SKYBLUE (-8025 4200);
FORCEPROP 2 LAST $SEC 1
J 0
(-8025 4300);
DISPLAY 0.680851 (-8025 4300);
PAINT MONO (-8025 4300);
DISPLAY INVISIBLE (-8025 4300);
FORCEPROP 2 LAST CDS_SEC 1
J 0
(-8025 4300);
DISPLAY 1.021277 (-8025 4300);
DISPLAY INVISIBLE (-8025 4300);
FORCEPROP 1 LASTPIN (-8075 4200) $PN 1
J 0
(-8065 4180);
DISPLAY 0.489362 (-8065 4180);
FORCEPROP 1 LASTPIN (-8075 4000) $PN 2
J 0
(-8065 3980);
DISPLAY 0.489362 (-8065 3980);
FORCEPROP 1 LAST MATERIAL X6S
J 0
(-8025 4000);
DISPLAY 0.489362 (-8025 4000);
PAINT SKYBLUE (-8025 4000);
FORCEPROP 1 LAST TOLERANCE 20%
J 0
(-8025 4050);
DISPLAY 0.489362 (-8025 4050);
PAINT SKYBLUE (-8025 4050);
FORCEPROP 1 LAST VALUE 22UF
J 0
(-8025 4150);
DISPLAY 0.489362 (-8025 4150);
PAINT SKYBLUE (-8025 4150);
FORCEPROP 1 LAST VOLTAGE 4V
J 0
(-8025 4100);
DISPLAY 0.489362 (-8025 4100);
PAINT SKYBLUE (-8025 4100);
FORCEPROP 1 LAST PACK_TYPE C0402
J 0
(-8025 3900);
DISPLAY 0.489362 (-8025 3900);
PAINT SKYBLUE (-8025 3900);
FORCEPROP 2 LAST CDS_LIB pure_quanta
J 0
(-8075 4100);
PAINT MONO (-8075 4100);
DISPLAY INVISIBLE (-8075 4100);
FORCEPROP 1 LAST PATH I30
J 0
(-8025 4250);
DISPLAY 0.978723 (-8025 4250);
PAINT WHITE (-8025 4250);
DISPLAY INVISIBLE (-8025 4250);
FORCEPROP 1 LAST PART_NUMBER CH622KMEB02
J 0
(-8025 3950);
DISPLAY 0.489362 (-8025 3950);
PAINT SKYBLUE (-8025 3950);
DISPLAY INVISIBLE (-8025 3950);
FORCEADD Q_CAP..1
(-8075 4900);
FORCEPROP 1 LAST LOCATION C2263
J 0
(-8025 5000);
DISPLAY 0.489362 (-8025 5000);
PAINT SKYBLUE (-8025 5000);
FORCEPROP 2 LAST $SEC 1
J 0
(-8025 5100);
DISPLAY 0.680851 (-8025 5100);
PAINT MONO (-8025 5100);
DISPLAY INVISIBLE (-8025 5100);
FORCEPROP 2 LAST CDS_SEC 1
J 0
(-8025 5100);
DISPLAY 1.021277 (-8025 5100);
DISPLAY INVISIBLE (-8025 5100);
FORCEPROP 1 LASTPIN (-8075 5000) $PN 1
J 0
(-8065 4980);
DISPLAY 0.489362 (-8065 4980);
FORCEPROP 1 LASTPIN (-8075 4800) $PN 2
J 0
(-8065 4780);
DISPLAY 0.489362 (-8065 4780);
FORCEPROP 1 LAST MATERIAL X6S
J 0
(-8025 4800);
DISPLAY 0.489362 (-8025 4800);
PAINT SKYBLUE (-8025 4800);
FORCEPROP 1 LAST TOLERANCE 20%
J 0
(-8025 4850);
DISPLAY 0.489362 (-8025 4850);
PAINT SKYBLUE (-8025 4850);
FORCEPROP 1 LAST VALUE 22UF
J 0
(-8025 4950);
DISPLAY 0.489362 (-8025 4950);
PAINT SKYBLUE (-8025 4950);
FORCEPROP 1 LAST VOLTAGE 4V
J 0
(-8025 4900);
DISPLAY 0.489362 (-8025 4900);
PAINT SKYBLUE (-8025 4900);
FORCEPROP 1 LAST PACK_TYPE C0402
J 0
(-8025 4700);
DISPLAY 0.489362 (-8025 4700);
PAINT SKYBLUE (-8025 4700);
FORCEPROP 2 LAST CDS_LIB pure_quanta
J 0
(-8075 4900);
PAINT MONO (-8075 4900);
DISPLAY INVISIBLE (-8075 4900);
FORCEPROP 1 LAST PATH I31
J 0
(-8025 5050);
DISPLAY 0.978723 (-8025 5050);
PAINT WHITE (-8025 5050);
DISPLAY INVISIBLE (-8025 5050);
FORCEPROP 1 LAST PART_NUMBER CH622KMEB02
J 0
(-8025 4750);
DISPLAY 0.489362 (-8025 4750);
PAINT SKYBLUE (-8025 4750);
DISPLAY INVISIBLE (-8025 4750);
FORCEADD Q_CAP..1
(-7625 4100);
FORCEPROP 1 LAST LOCATION C2269
J 0
(-7575 4200);
DISPLAY 0.489362 (-7575 4200);
PAINT SKYBLUE (-7575 4200);
FORCEPROP 2 LAST $SEC 1
J 0
(-7575 4300);
DISPLAY 0.680851 (-7575 4300);
PAINT MONO (-7575 4300);
DISPLAY INVISIBLE (-7575 4300);
FORCEPROP 2 LAST CDS_SEC 1
J 0
(-7575 4300);
DISPLAY 1.021277 (-7575 4300);
DISPLAY INVISIBLE (-7575 4300);
FORCEPROP 1 LASTPIN (-7625 4200) $PN 1
J 0
(-7615 4180);
DISPLAY 0.489362 (-7615 4180);
FORCEPROP 1 LASTPIN (-7625 4000) $PN 2
J 0
(-7615 3980);
DISPLAY 0.489362 (-7615 3980);
FORCEPROP 1 LAST MATERIAL X6S
J 0
(-7575 4000);
DISPLAY 0.489362 (-7575 4000);
PAINT SKYBLUE (-7575 4000);
FORCEPROP 1 LAST TOLERANCE 20%
J 0
(-7575 4050);
DISPLAY 0.489362 (-7575 4050);
PAINT SKYBLUE (-7575 4050);
FORCEPROP 1 LAST VALUE 22UF
J 0
(-7575 4150);
DISPLAY 0.489362 (-7575 4150);
PAINT SKYBLUE (-7575 4150);
FORCEPROP 1 LAST VOLTAGE 4V
J 0
(-7575 4100);
DISPLAY 0.489362 (-7575 4100);
PAINT SKYBLUE (-7575 4100);
FORCEPROP 1 LAST PACK_TYPE C0402
J 0
(-7575 3900);
DISPLAY 0.489362 (-7575 3900);
PAINT SKYBLUE (-7575 3900);
FORCEPROP 2 LAST CDS_LIB pure_quanta
J 0
(-7625 4100);
PAINT MONO (-7625 4100);
DISPLAY INVISIBLE (-7625 4100);
FORCEPROP 1 LAST PATH I32
J 0
(-7575 4250);
DISPLAY 0.978723 (-7575 4250);
PAINT WHITE (-7575 4250);
DISPLAY INVISIBLE (-7575 4250);
FORCEPROP 1 LAST PART_NUMBER CH622KMEB02
J 0
(-7575 3950);
DISPLAY 0.489362 (-7575 3950);
PAINT SKYBLUE (-7575 3950);
DISPLAY INVISIBLE (-7575 3950);
FORCEADD Q_CAP..1
(-7625 4900);
FORCEPROP 1 LAST LOCATION C2268
J 0
(-7575 5000);
DISPLAY 0.489362 (-7575 5000);
PAINT SKYBLUE (-7575 5000);
FORCEPROP 2 LAST $SEC 1
J 0
(-7575 5100);
DISPLAY 0.680851 (-7575 5100);
PAINT MONO (-7575 5100);
DISPLAY INVISIBLE (-7575 5100);
FORCEPROP 2 LAST CDS_SEC 1
J 0
(-7575 5100);
DISPLAY 1.021277 (-7575 5100);
DISPLAY INVISIBLE (-7575 5100);
FORCEPROP 1 LASTPIN (-7625 5000) $PN 1
J 0
(-7615 4980);
DISPLAY 0.489362 (-7615 4980);
FORCEPROP 1 LASTPIN (-7625 4800) $PN 2
J 0
(-7615 4780);
DISPLAY 0.489362 (-7615 4780);
FORCEPROP 1 LAST MATERIAL X6S
J 0
(-7575 4800);
DISPLAY 0.489362 (-7575 4800);
PAINT SKYBLUE (-7575 4800);
FORCEPROP 1 LAST TOLERANCE 20%
J 0
(-7575 4850);
DISPLAY 0.489362 (-7575 4850);
PAINT SKYBLUE (-7575 4850);
FORCEPROP 1 LAST VALUE 22UF
J 0
(-7575 4950);
DISPLAY 0.489362 (-7575 4950);
PAINT SKYBLUE (-7575 4950);
FORCEPROP 1 LAST VOLTAGE 4V
J 0
(-7575 4900);
DISPLAY 0.489362 (-7575 4900);
PAINT SKYBLUE (-7575 4900);
FORCEPROP 1 LAST PACK_TYPE C0402
J 0
(-7575 4700);
DISPLAY 0.489362 (-7575 4700);
PAINT SKYBLUE (-7575 4700);
FORCEPROP 2 LAST CDS_LIB pure_quanta
J 0
(-7625 4900);
PAINT MONO (-7625 4900);
DISPLAY INVISIBLE (-7625 4900);
FORCEPROP 1 LAST PATH I33
J 0
(-7575 5050);
DISPLAY 0.978723 (-7575 5050);
PAINT WHITE (-7575 5050);
DISPLAY INVISIBLE (-7575 5050);
FORCEPROP 1 LAST PART_NUMBER CH622KMEB02
J 0
(-7575 4750);
DISPLAY 0.489362 (-7575 4750);
PAINT SKYBLUE (-7575 4750);
DISPLAY INVISIBLE (-7575 4750);
FORCEADD Q_CAP..1
(-7175 4900);
FORCEPROP 1 LAST LOCATION C2272
J 0
(-7125 5000);
DISPLAY 0.489362 (-7125 5000);
PAINT SKYBLUE (-7125 5000);
FORCEPROP 2 LAST $SEC 1
J 0
(-7125 5100);
DISPLAY 0.680851 (-7125 5100);
PAINT MONO (-7125 5100);
DISPLAY INVISIBLE (-7125 5100);
FORCEPROP 2 LAST CDS_SEC 1
J 0
(-7125 5100);
DISPLAY 1.021277 (-7125 5100);
DISPLAY INVISIBLE (-7125 5100);
FORCEPROP 1 LASTPIN (-7175 5000) $PN 1
J 0
(-7165 4980);
DISPLAY 0.489362 (-7165 4980);
FORCEPROP 1 LASTPIN (-7175 4800) $PN 2
J 0
(-7165 4780);
DISPLAY 0.489362 (-7165 4780);
FORCEPROP 1 LAST MATERIAL X6S
J 0
(-7125 4800);
DISPLAY 0.489362 (-7125 4800);
PAINT SKYBLUE (-7125 4800);
FORCEPROP 1 LAST TOLERANCE 20%
J 0
(-7125 4850);
DISPLAY 0.489362 (-7125 4850);
PAINT SKYBLUE (-7125 4850);
FORCEPROP 1 LAST VALUE 22UF
J 0
(-7125 4950);
DISPLAY 0.489362 (-7125 4950);
PAINT SKYBLUE (-7125 4950);
FORCEPROP 1 LAST VOLTAGE 4V
J 0
(-7125 4900);
DISPLAY 0.489362 (-7125 4900);
PAINT SKYBLUE (-7125 4900);
FORCEPROP 1 LAST PACK_TYPE C0402
J 0
(-7125 4700);
DISPLAY 0.489362 (-7125 4700);
PAINT SKYBLUE (-7125 4700);
FORCEPROP 2 LAST CDS_LIB pure_quanta
J 0
(-7175 4900);
PAINT MONO (-7175 4900);
DISPLAY INVISIBLE (-7175 4900);
FORCEPROP 1 LAST PATH I34
J 0
(-7125 5050);
DISPLAY 0.978723 (-7125 5050);
PAINT WHITE (-7125 5050);
DISPLAY INVISIBLE (-7125 5050);
FORCEPROP 1 LAST PART_NUMBER CH622KMEB02
J 0
(-7125 4750);
DISPLAY 0.489362 (-7125 4750);
PAINT SKYBLUE (-7125 4750);
DISPLAY INVISIBLE (-7125 4750);
FORCEADD Q_CAP..1
(-7175 4100);
FORCEPROP 1 LAST LOCATION C2273
J 0
(-7125 4200);
DISPLAY 0.489362 (-7125 4200);
PAINT SKYBLUE (-7125 4200);
FORCEPROP 2 LAST $SEC 1
J 0
(-7125 4300);
DISPLAY 0.680851 (-7125 4300);
PAINT MONO (-7125 4300);
DISPLAY INVISIBLE (-7125 4300);
FORCEPROP 2 LAST CDS_SEC 1
J 0
(-7125 4300);
DISPLAY 1.021277 (-7125 4300);
DISPLAY INVISIBLE (-7125 4300);
FORCEPROP 1 LASTPIN (-7175 4200) $PN 1
J 0
(-7165 4180);
DISPLAY 0.489362 (-7165 4180);
FORCEPROP 1 LASTPIN (-7175 4000) $PN 2
J 0
(-7165 3980);
DISPLAY 0.489362 (-7165 3980);
FORCEPROP 1 LAST MATERIAL X6S
J 0
(-7125 4000);
DISPLAY 0.489362 (-7125 4000);
PAINT SKYBLUE (-7125 4000);
FORCEPROP 1 LAST TOLERANCE 20%
J 0
(-7125 4050);
DISPLAY 0.489362 (-7125 4050);
PAINT SKYBLUE (-7125 4050);
FORCEPROP 1 LAST VALUE 22UF
J 0
(-7125 4150);
DISPLAY 0.489362 (-7125 4150);
PAINT SKYBLUE (-7125 4150);
FORCEPROP 1 LAST VOLTAGE 4V
J 0
(-7125 4100);
DISPLAY 0.489362 (-7125 4100);
PAINT SKYBLUE (-7125 4100);
FORCEPROP 1 LAST PACK_TYPE C0402
J 0
(-7125 3900);
DISPLAY 0.489362 (-7125 3900);
PAINT SKYBLUE (-7125 3900);
FORCEPROP 2 LAST CDS_LIB pure_quanta
J 0
(-7175 4100);
PAINT MONO (-7175 4100);
DISPLAY INVISIBLE (-7175 4100);
FORCEPROP 1 LAST PATH I35
J 0
(-7125 4250);
DISPLAY 0.978723 (-7125 4250);
PAINT WHITE (-7125 4250);
DISPLAY INVISIBLE (-7125 4250);
FORCEPROP 1 LAST PART_NUMBER CH622KMEB02
J 0
(-7125 3950);
DISPLAY 0.489362 (-7125 3950);
PAINT SKYBLUE (-7125 3950);
DISPLAY INVISIBLE (-7125 3950);
FORCEADD Q_CAP..1
(-6725 4100);
FORCEPROP 1 LAST LOCATION C2277
J 0
(-6675 4200);
DISPLAY 0.489362 (-6675 4200);
PAINT SKYBLUE (-6675 4200);
FORCEPROP 2 LAST $SEC 1
J 0
(-6675 4300);
DISPLAY 0.680851 (-6675 4300);
PAINT MONO (-6675 4300);
DISPLAY INVISIBLE (-6675 4300);
FORCEPROP 2 LAST CDS_SEC 1
J 0
(-6675 4300);
DISPLAY 1.021277 (-6675 4300);
DISPLAY INVISIBLE (-6675 4300);
FORCEPROP 1 LASTPIN (-6725 4200) $PN 1
J 0
(-6715 4180);
DISPLAY 0.489362 (-6715 4180);
FORCEPROP 1 LASTPIN (-6725 4000) $PN 2
J 0
(-6715 3980);
DISPLAY 0.489362 (-6715 3980);
FORCEPROP 1 LAST MATERIAL X6S
J 0
(-6675 4000);
DISPLAY 0.489362 (-6675 4000);
PAINT SKYBLUE (-6675 4000);
FORCEPROP 1 LAST TOLERANCE 20%
J 0
(-6675 4050);
DISPLAY 0.489362 (-6675 4050);
PAINT SKYBLUE (-6675 4050);
FORCEPROP 1 LAST VALUE 22UF
J 0
(-6675 4150);
DISPLAY 0.489362 (-6675 4150);
PAINT SKYBLUE (-6675 4150);
FORCEPROP 1 LAST VOLTAGE 4V
J 0
(-6675 4100);
DISPLAY 0.489362 (-6675 4100);
PAINT SKYBLUE (-6675 4100);
FORCEPROP 1 LAST PACK_TYPE C0402
J 0
(-6675 3900);
DISPLAY 0.489362 (-6675 3900);
PAINT SKYBLUE (-6675 3900);
FORCEPROP 2 LAST CDS_LIB pure_quanta
J 0
(-6725 4100);
PAINT MONO (-6725 4100);
DISPLAY INVISIBLE (-6725 4100);
FORCEPROP 1 LAST PATH I36
J 0
(-6675 4250);
DISPLAY 0.978723 (-6675 4250);
PAINT WHITE (-6675 4250);
DISPLAY INVISIBLE (-6675 4250);
FORCEPROP 1 LAST PART_NUMBER CH622KMEB02
J 0
(-6675 3950);
DISPLAY 0.489362 (-6675 3950);
PAINT SKYBLUE (-6675 3950);
DISPLAY INVISIBLE (-6675 3950);
FORCEADD Q_CAP..1
(-6275 4100);
FORCEPROP 1 LAST LOCATION C2281
J 0
(-6225 4200);
DISPLAY 0.489362 (-6225 4200);
PAINT SKYBLUE (-6225 4200);
FORCEPROP 2 LAST $SEC 1
J 0
(-6225 4300);
DISPLAY 0.680851 (-6225 4300);
PAINT MONO (-6225 4300);
DISPLAY INVISIBLE (-6225 4300);
FORCEPROP 2 LAST CDS_SEC 1
J 0
(-6225 4300);
DISPLAY 1.021277 (-6225 4300);
DISPLAY INVISIBLE (-6225 4300);
FORCEPROP 1 LASTPIN (-6275 4200) $PN 1
J 0
(-6265 4180);
DISPLAY 0.489362 (-6265 4180);
FORCEPROP 1 LASTPIN (-6275 4000) $PN 2
J 0
(-6265 3980);
DISPLAY 0.489362 (-6265 3980);
FORCEPROP 1 LAST MATERIAL X6S
J 0
(-6225 4000);
DISPLAY 0.489362 (-6225 4000);
PAINT SKYBLUE (-6225 4000);
FORCEPROP 1 LAST TOLERANCE 20%
J 0
(-6225 4050);
DISPLAY 0.489362 (-6225 4050);
PAINT SKYBLUE (-6225 4050);
FORCEPROP 1 LAST VALUE 22UF
J 0
(-6225 4150);
DISPLAY 0.489362 (-6225 4150);
PAINT SKYBLUE (-6225 4150);
FORCEPROP 1 LAST VOLTAGE 4V
J 0
(-6225 4100);
DISPLAY 0.489362 (-6225 4100);
PAINT SKYBLUE (-6225 4100);
FORCEPROP 1 LAST PACK_TYPE C0402
J 0
(-6225 3900);
DISPLAY 0.489362 (-6225 3900);
PAINT SKYBLUE (-6225 3900);
FORCEPROP 2 LAST CDS_LIB pure_quanta
J 0
(-6275 4100);
PAINT MONO (-6275 4100);
DISPLAY INVISIBLE (-6275 4100);
FORCEPROP 1 LAST PATH I37
J 0
(-6225 4250);
DISPLAY 0.978723 (-6225 4250);
PAINT WHITE (-6225 4250);
DISPLAY INVISIBLE (-6225 4250);
FORCEPROP 1 LAST PART_NUMBER CH622KMEB02
J 0
(-6225 3950);
DISPLAY 0.489362 (-6225 3950);
PAINT SKYBLUE (-6225 3950);
DISPLAY INVISIBLE (-6225 3950);
FORCEADD Q_CAP..1
(-6275 4900);
FORCEPROP 1 LAST LOCATION C2280
J 0
(-6225 5000);
DISPLAY 0.489362 (-6225 5000);
PAINT SKYBLUE (-6225 5000);
FORCEPROP 2 LAST $SEC 1
J 0
(-6225 5100);
DISPLAY 0.680851 (-6225 5100);
PAINT MONO (-6225 5100);
DISPLAY INVISIBLE (-6225 5100);
FORCEPROP 2 LAST CDS_SEC 1
J 0
(-6225 5100);
DISPLAY 1.021277 (-6225 5100);
DISPLAY INVISIBLE (-6225 5100);
FORCEPROP 1 LASTPIN (-6275 5000) $PN 1
J 0
(-6265 4980);
DISPLAY 0.489362 (-6265 4980);
FORCEPROP 1 LASTPIN (-6275 4800) $PN 2
J 0
(-6265 4780);
DISPLAY 0.489362 (-6265 4780);
FORCEPROP 1 LAST MATERIAL X6S
J 0
(-6225 4800);
DISPLAY 0.489362 (-6225 4800);
PAINT SKYBLUE (-6225 4800);
FORCEPROP 1 LAST TOLERANCE 20%
J 0
(-6225 4850);
DISPLAY 0.489362 (-6225 4850);
PAINT SKYBLUE (-6225 4850);
FORCEPROP 1 LAST VALUE 22UF
J 0
(-6225 4950);
DISPLAY 0.489362 (-6225 4950);
PAINT SKYBLUE (-6225 4950);
FORCEPROP 1 LAST VOLTAGE 4V
J 0
(-6225 4900);
DISPLAY 0.489362 (-6225 4900);
PAINT SKYBLUE (-6225 4900);
FORCEPROP 1 LAST PACK_TYPE C0402
J 0
(-6225 4700);
DISPLAY 0.489362 (-6225 4700);
PAINT SKYBLUE (-6225 4700);
FORCEPROP 2 LAST CDS_LIB pure_quanta
J 0
(-6275 4900);
PAINT MONO (-6275 4900);
DISPLAY INVISIBLE (-6275 4900);
FORCEPROP 1 LAST PATH I38
J 0
(-6225 5050);
DISPLAY 0.978723 (-6225 5050);
PAINT WHITE (-6225 5050);
DISPLAY INVISIBLE (-6225 5050);
FORCEPROP 1 LAST PART_NUMBER CH622KMEB02
J 0
(-6225 4750);
DISPLAY 0.489362 (-6225 4750);
PAINT SKYBLUE (-6225 4750);
DISPLAY INVISIBLE (-6225 4750);
FORCEADD Q_CAP..1
(-5825 4100);
FORCEPROP 1 LAST LOCATION C2284
J 0
(-5775 4200);
DISPLAY 0.489362 (-5775 4200);
PAINT SKYBLUE (-5775 4200);
FORCEPROP 2 LAST $SEC 1
J 0
(-5775 4300);
DISPLAY 0.680851 (-5775 4300);
PAINT MONO (-5775 4300);
DISPLAY INVISIBLE (-5775 4300);
FORCEPROP 2 LAST CDS_SEC 1
J 0
(-5775 4300);
DISPLAY 1.021277 (-5775 4300);
DISPLAY INVISIBLE (-5775 4300);
FORCEPROP 1 LASTPIN (-5825 4200) $PN 1
J 0
(-5815 4180);
DISPLAY 0.489362 (-5815 4180);
FORCEPROP 1 LASTPIN (-5825 4000) $PN 2
J 0
(-5815 3980);
DISPLAY 0.489362 (-5815 3980);
FORCEPROP 1 LAST MATERIAL X6S
J 0
(-5775 4000);
DISPLAY 0.489362 (-5775 4000);
PAINT SKYBLUE (-5775 4000);
FORCEPROP 1 LAST TOLERANCE 20%
J 0
(-5775 4050);
DISPLAY 0.489362 (-5775 4050);
PAINT SKYBLUE (-5775 4050);
FORCEPROP 1 LAST VALUE 22UF
J 0
(-5775 4150);
DISPLAY 0.489362 (-5775 4150);
PAINT SKYBLUE (-5775 4150);
FORCEPROP 1 LAST VOLTAGE 4V
J 0
(-5775 4100);
DISPLAY 0.489362 (-5775 4100);
PAINT SKYBLUE (-5775 4100);
FORCEPROP 1 LAST PACK_TYPE C0402
J 0
(-5775 3900);
DISPLAY 0.489362 (-5775 3900);
PAINT SKYBLUE (-5775 3900);
FORCEPROP 2 LAST CDS_LIB pure_quanta
J 0
(-5825 4100);
PAINT MONO (-5825 4100);
DISPLAY INVISIBLE (-5825 4100);
FORCEPROP 1 LAST PATH I39
J 0
(-5775 4250);
DISPLAY 0.978723 (-5775 4250);
PAINT WHITE (-5775 4250);
DISPLAY INVISIBLE (-5775 4250);
FORCEPROP 1 LAST PART_NUMBER CH622KMEB02
J 0
(-5775 3950);
DISPLAY 0.489362 (-5775 3950);
PAINT SKYBLUE (-5775 3950);
DISPLAY INVISIBLE (-5775 3950);
FORCEADD UNIVERSAL_POWER..1
(-8500 1850);
FORCEPROP 3 LASTPIN (-8500 1800) SIG_NAME PVDD11_S3_P1\g
J 0
(-8490 1810);
DISPLAY 0.659574 (-8490 1810);
PAINT MONO (-8490 1810);
DISPLAY INVISIBLE (-8490 1810);
FORCEPROP 1 LAST HDL_POWER PVDD11_S3_P1
J 1
(-8500 1900);
DISPLAY 0.489362 (-8500 1900);
PAINT GREEN (-8500 1900);
FORCEPROP 2 LAST CDS_LIB pure_quanta_power
J 0
(-8500 1850);
DISPLAY INVISIBLE (-8500 1850);
FORCEPROP 1 LAST PATH I4
J 0
(-8450 1875);
DISPLAY 0.872340 (-8450 1875);
PAINT AQUA (-8450 1875);
DISPLAY INVISIBLE (-8450 1875);
FORCEADD Q_CAP..1
(-5825 4900);
FORCEPROP 1 LAST LOCATION C2283
J 0
(-5775 5000);
DISPLAY 0.489362 (-5775 5000);
PAINT SKYBLUE (-5775 5000);
FORCEPROP 2 LAST $SEC 1
J 0
(-5775 5100);
DISPLAY 0.680851 (-5775 5100);
PAINT MONO (-5775 5100);
DISPLAY INVISIBLE (-5775 5100);
FORCEPROP 2 LAST CDS_SEC 1
J 0
(-5775 5100);
DISPLAY 1.021277 (-5775 5100);
DISPLAY INVISIBLE (-5775 5100);
FORCEPROP 1 LASTPIN (-5825 5000) $PN 1
J 0
(-5815 4980);
DISPLAY 0.489362 (-5815 4980);
FORCEPROP 1 LASTPIN (-5825 4800) $PN 2
J 0
(-5815 4780);
DISPLAY 0.489362 (-5815 4780);
FORCEPROP 1 LAST MATERIAL X6S
J 0
(-5775 4800);
DISPLAY 0.489362 (-5775 4800);
PAINT SKYBLUE (-5775 4800);
FORCEPROP 1 LAST TOLERANCE 20%
J 0
(-5775 4850);
DISPLAY 0.489362 (-5775 4850);
PAINT SKYBLUE (-5775 4850);
FORCEPROP 1 LAST VALUE 22UF
J 0
(-5775 4950);
DISPLAY 0.489362 (-5775 4950);
PAINT SKYBLUE (-5775 4950);
FORCEPROP 1 LAST VOLTAGE 4V
J 0
(-5775 4900);
DISPLAY 0.489362 (-5775 4900);
PAINT SKYBLUE (-5775 4900);
FORCEPROP 1 LAST PACK_TYPE C0402
J 0
(-5775 4700);
DISPLAY 0.489362 (-5775 4700);
PAINT SKYBLUE (-5775 4700);
FORCEPROP 2 LAST CDS_LIB pure_quanta
J 0
(-5825 4900);
PAINT MONO (-5825 4900);
DISPLAY INVISIBLE (-5825 4900);
FORCEPROP 1 LAST PATH I40
J 0
(-5775 5050);
DISPLAY 0.978723 (-5775 5050);
PAINT WHITE (-5775 5050);
DISPLAY INVISIBLE (-5775 5050);
FORCEPROP 1 LAST PART_NUMBER CH622KMEB02
J 0
(-5775 4750);
DISPLAY 0.489362 (-5775 4750);
PAINT SKYBLUE (-5775 4750);
DISPLAY INVISIBLE (-5775 4750);
FORCEADD Q_CAP..1
(-5375 4100);
FORCEPROP 1 LAST LOCATION C3906
J 0
(-5325 4200);
DISPLAY 0.489362 (-5325 4200);
PAINT SKYBLUE (-5325 4200);
FORCEPROP 2 LAST $SEC 1
J 0
(-5325 4300);
DISPLAY 0.680851 (-5325 4300);
PAINT MONO (-5325 4300);
DISPLAY INVISIBLE (-5325 4300);
FORCEPROP 2 LAST CDS_SEC 1
J 0
(-5325 4300);
DISPLAY 1.021277 (-5325 4300);
DISPLAY INVISIBLE (-5325 4300);
FORCEPROP 1 LASTPIN (-5375 4200) $PN 1
J 0
(-5365 4180);
DISPLAY 0.489362 (-5365 4180);
FORCEPROP 1 LASTPIN (-5375 4000) $PN 2
J 0
(-5365 3980);
DISPLAY 0.489362 (-5365 3980);
FORCEPROP 1 LAST MATERIAL X6S
J 0
(-5325 4000);
DISPLAY 0.489362 (-5325 4000);
PAINT SKYBLUE (-5325 4000);
FORCEPROP 1 LAST TOLERANCE 20%
J 0
(-5325 4050);
DISPLAY 0.489362 (-5325 4050);
PAINT SKYBLUE (-5325 4050);
FORCEPROP 1 LAST VALUE 22UF
J 0
(-5325 4150);
DISPLAY 0.489362 (-5325 4150);
PAINT SKYBLUE (-5325 4150);
FORCEPROP 1 LAST VOLTAGE 4V
J 0
(-5325 4100);
DISPLAY 0.489362 (-5325 4100);
PAINT SKYBLUE (-5325 4100);
FORCEPROP 1 LAST PACK_TYPE C0402
J 0
(-5325 3900);
DISPLAY 0.489362 (-5325 3900);
PAINT SKYBLUE (-5325 3900);
FORCEPROP 2 LAST CDS_LIB pure_quanta
J 0
(-5375 4100);
PAINT MONO (-5375 4100);
DISPLAY INVISIBLE (-5375 4100);
FORCEPROP 1 LAST PATH I41
J 0
(-5325 4250);
DISPLAY 0.978723 (-5325 4250);
PAINT WHITE (-5325 4250);
DISPLAY INVISIBLE (-5325 4250);
FORCEPROP 1 LAST PART_NUMBER CH622KMEB02
J 0
(-5325 3950);
DISPLAY 0.489362 (-5325 3950);
PAINT SKYBLUE (-5325 3950);
DISPLAY INVISIBLE (-5325 3950);
FORCEADD Q_CAP..1
(-5375 4900);
FORCEPROP 1 LAST LOCATION C2286
J 0
(-5325 5000);
DISPLAY 0.489362 (-5325 5000);
PAINT SKYBLUE (-5325 5000);
FORCEPROP 2 LAST $SEC 1
J 0
(-5325 5100);
DISPLAY 0.680851 (-5325 5100);
PAINT MONO (-5325 5100);
DISPLAY INVISIBLE (-5325 5100);
FORCEPROP 2 LAST CDS_SEC 1
J 0
(-5325 5100);
DISPLAY 1.021277 (-5325 5100);
DISPLAY INVISIBLE (-5325 5100);
FORCEPROP 1 LASTPIN (-5375 5000) $PN 1
J 0
(-5365 4980);
DISPLAY 0.489362 (-5365 4980);
FORCEPROP 1 LASTPIN (-5375 4800) $PN 2
J 0
(-5365 4780);
DISPLAY 0.489362 (-5365 4780);
FORCEPROP 1 LAST MATERIAL X6S
J 0
(-5325 4800);
DISPLAY 0.489362 (-5325 4800);
PAINT SKYBLUE (-5325 4800);
FORCEPROP 1 LAST TOLERANCE 20%
J 0
(-5325 4850);
DISPLAY 0.489362 (-5325 4850);
PAINT SKYBLUE (-5325 4850);
FORCEPROP 1 LAST VALUE 22UF
J 0
(-5325 4950);
DISPLAY 0.489362 (-5325 4950);
PAINT SKYBLUE (-5325 4950);
FORCEPROP 1 LAST VOLTAGE 4V
J 0
(-5325 4900);
DISPLAY 0.489362 (-5325 4900);
PAINT SKYBLUE (-5325 4900);
FORCEPROP 1 LAST PACK_TYPE C0402
J 0
(-5325 4700);
DISPLAY 0.489362 (-5325 4700);
PAINT SKYBLUE (-5325 4700);
FORCEPROP 2 LAST CDS_LIB pure_quanta
J 0
(-5375 4900);
PAINT MONO (-5375 4900);
DISPLAY INVISIBLE (-5375 4900);
FORCEPROP 1 LAST PATH I42
J 0
(-5325 5050);
DISPLAY 0.978723 (-5325 5050);
PAINT WHITE (-5325 5050);
DISPLAY INVISIBLE (-5325 5050);
FORCEPROP 1 LAST PART_NUMBER CH622KMEB02
J 0
(-5325 4750);
DISPLAY 0.489362 (-5325 4750);
PAINT SKYBLUE (-5325 4750);
DISPLAY INVISIBLE (-5325 4750);
FORCEADD Q_CAP..1
(-4925 4100);
FORCEPROP 1 LAST LOCATION C3907
J 0
(-4875 4200);
DISPLAY 0.489362 (-4875 4200);
PAINT SKYBLUE (-4875 4200);
FORCEPROP 2 LAST $SEC 1
J 0
(-4875 4300);
DISPLAY 0.680851 (-4875 4300);
PAINT MONO (-4875 4300);
DISPLAY INVISIBLE (-4875 4300);
FORCEPROP 2 LAST CDS_SEC 1
J 0
(-4875 4300);
DISPLAY 1.021277 (-4875 4300);
DISPLAY INVISIBLE (-4875 4300);
FORCEPROP 1 LASTPIN (-4925 4200) $PN 1
J 0
(-4915 4180);
DISPLAY 0.489362 (-4915 4180);
FORCEPROP 1 LASTPIN (-4925 4000) $PN 2
J 0
(-4915 3980);
DISPLAY 0.489362 (-4915 3980);
FORCEPROP 1 LAST MATERIAL X6S
J 0
(-4875 4000);
DISPLAY 0.489362 (-4875 4000);
PAINT SKYBLUE (-4875 4000);
FORCEPROP 1 LAST TOLERANCE 20%
J 0
(-4875 4050);
DISPLAY 0.489362 (-4875 4050);
PAINT SKYBLUE (-4875 4050);
FORCEPROP 1 LAST VALUE 22UF
J 0
(-4875 4150);
DISPLAY 0.489362 (-4875 4150);
PAINT SKYBLUE (-4875 4150);
FORCEPROP 1 LAST VOLTAGE 4V
J 0
(-4875 4100);
DISPLAY 0.489362 (-4875 4100);
PAINT SKYBLUE (-4875 4100);
FORCEPROP 1 LAST PACK_TYPE C0402
J 0
(-4875 3900);
DISPLAY 0.489362 (-4875 3900);
PAINT SKYBLUE (-4875 3900);
FORCEPROP 2 LAST CDS_LIB pure_quanta
J 0
(-4925 4100);
PAINT MONO (-4925 4100);
DISPLAY INVISIBLE (-4925 4100);
FORCEPROP 1 LAST PATH I43
J 0
(-4875 4250);
DISPLAY 0.978723 (-4875 4250);
PAINT WHITE (-4875 4250);
DISPLAY INVISIBLE (-4875 4250);
FORCEPROP 1 LAST PART_NUMBER CH622KMEB02
J 0
(-4875 3950);
DISPLAY 0.489362 (-4875 3950);
PAINT SKYBLUE (-4875 3950);
DISPLAY INVISIBLE (-4875 3950);
FORCEADD Q_CAP..1
(-4925 4900);
FORCEPROP 1 LAST LOCATION C2288
J 0
(-4875 5000);
DISPLAY 0.489362 (-4875 5000);
PAINT SKYBLUE (-4875 5000);
FORCEPROP 2 LAST $SEC 1
J 0
(-4875 5100);
DISPLAY 0.680851 (-4875 5100);
PAINT MONO (-4875 5100);
DISPLAY INVISIBLE (-4875 5100);
FORCEPROP 2 LAST CDS_SEC 1
J 0
(-4875 5100);
DISPLAY 1.021277 (-4875 5100);
DISPLAY INVISIBLE (-4875 5100);
FORCEPROP 1 LASTPIN (-4925 5000) $PN 1
J 0
(-4915 4980);
DISPLAY 0.489362 (-4915 4980);
FORCEPROP 1 LASTPIN (-4925 4800) $PN 2
J 0
(-4915 4780);
DISPLAY 0.489362 (-4915 4780);
FORCEPROP 1 LAST MATERIAL X6S
J 0
(-4875 4800);
DISPLAY 0.489362 (-4875 4800);
PAINT SKYBLUE (-4875 4800);
FORCEPROP 1 LAST TOLERANCE 20%
J 0
(-4875 4850);
DISPLAY 0.489362 (-4875 4850);
PAINT SKYBLUE (-4875 4850);
FORCEPROP 1 LAST VALUE 22UF
J 0
(-4875 4950);
DISPLAY 0.489362 (-4875 4950);
PAINT SKYBLUE (-4875 4950);
FORCEPROP 1 LAST VOLTAGE 4V
J 0
(-4875 4900);
DISPLAY 0.489362 (-4875 4900);
PAINT SKYBLUE (-4875 4900);
FORCEPROP 1 LAST PACK_TYPE C0402
J 0
(-4875 4700);
DISPLAY 0.489362 (-4875 4700);
PAINT SKYBLUE (-4875 4700);
FORCEPROP 2 LAST CDS_LIB pure_quanta
J 0
(-4925 4900);
PAINT MONO (-4925 4900);
DISPLAY INVISIBLE (-4925 4900);
FORCEPROP 1 LAST PATH I44
J 0
(-4875 5050);
DISPLAY 0.978723 (-4875 5050);
PAINT WHITE (-4875 5050);
DISPLAY INVISIBLE (-4875 5050);
FORCEPROP 1 LAST PART_NUMBER CH622KMEB02
J 0
(-4875 4750);
DISPLAY 0.489362 (-4875 4750);
PAINT SKYBLUE (-4875 4750);
DISPLAY INVISIBLE (-4875 4750);
FORCEADD Q_CAP..1
(-4525 4100);
FORCEPROP 1 LAST LOCATION C3908
J 0
(-4475 4200);
DISPLAY 0.489362 (-4475 4200);
PAINT SKYBLUE (-4475 4200);
FORCEPROP 2 LAST $SEC 1
J 0
(-4475 4300);
DISPLAY 0.680851 (-4475 4300);
PAINT MONO (-4475 4300);
DISPLAY INVISIBLE (-4475 4300);
FORCEPROP 2 LAST CDS_SEC 1
J 0
(-4475 4300);
DISPLAY 1.021277 (-4475 4300);
DISPLAY INVISIBLE (-4475 4300);
FORCEPROP 1 LASTPIN (-4525 4200) $PN 1
J 0
(-4515 4180);
DISPLAY 0.489362 (-4515 4180);
FORCEPROP 1 LASTPIN (-4525 4000) $PN 2
J 0
(-4515 3980);
DISPLAY 0.489362 (-4515 3980);
FORCEPROP 1 LAST MATERIAL X6S
J 0
(-4475 4000);
DISPLAY 0.489362 (-4475 4000);
PAINT SKYBLUE (-4475 4000);
FORCEPROP 1 LAST TOLERANCE 20%
J 0
(-4475 4050);
DISPLAY 0.489362 (-4475 4050);
PAINT SKYBLUE (-4475 4050);
FORCEPROP 1 LAST VALUE 22UF
J 0
(-4475 4150);
DISPLAY 0.489362 (-4475 4150);
PAINT SKYBLUE (-4475 4150);
FORCEPROP 1 LAST VOLTAGE 4V
J 0
(-4475 4100);
DISPLAY 0.489362 (-4475 4100);
PAINT SKYBLUE (-4475 4100);
FORCEPROP 1 LAST PACK_TYPE C0402
J 0
(-4475 3900);
DISPLAY 0.489362 (-4475 3900);
PAINT SKYBLUE (-4475 3900);
FORCEPROP 2 LAST CDS_LIB pure_quanta
J 0
(-4525 4100);
PAINT MONO (-4525 4100);
DISPLAY INVISIBLE (-4525 4100);
FORCEPROP 1 LAST PATH I45
J 0
(-4475 4250);
DISPLAY 0.978723 (-4475 4250);
PAINT WHITE (-4475 4250);
DISPLAY INVISIBLE (-4475 4250);
FORCEPROP 1 LAST PART_NUMBER CH622KMEB02
J 0
(-4475 3950);
DISPLAY 0.489362 (-4475 3950);
PAINT SKYBLUE (-4475 3950);
DISPLAY INVISIBLE (-4475 3950);
FORCEADD UNIVERSAL_GND..1
(-4525 4525);
FORCEPROP 3 LASTPIN (-4525 4575) SIG_NAME GND\g
J 0
(-4515 4585);
DISPLAY 0.659574 (-4515 4585);
PAINT MONO (-4515 4585);
DISPLAY INVISIBLE (-4515 4585);
FORCEPROP 2 LAST CDS_LIB pure_quanta_power
J 0
(-4525 4525);
PAINT MONO (-4525 4525);
DISPLAY INVISIBLE (-4525 4525);
FORCEPROP 1 LAST HDL_POWER GND
J 1
(-4500 4450);
DISPLAY 0.872340 (-4500 4450);
PAINT GREEN (-4500 4450);
DISPLAY INVISIBLE (-4500 4450);
FORCEPROP 1 LAST PATH I46
J 0
(-4450 4525);
DISPLAY 0.872340 (-4450 4525);
PAINT AQUA (-4450 4525);
DISPLAY INVISIBLE (-4450 4525);
FORCEADD Q_CAP..1
(-4525 4900);
FORCEPROP 1 LAST LOCATION C2290
J 0
(-4475 5000);
DISPLAY 0.489362 (-4475 5000);
PAINT SKYBLUE (-4475 5000);
FORCEPROP 2 LAST $SEC 1
J 0
(-4475 5100);
DISPLAY 0.680851 (-4475 5100);
PAINT MONO (-4475 5100);
DISPLAY INVISIBLE (-4475 5100);
FORCEPROP 2 LAST CDS_SEC 1
J 0
(-4475 5100);
DISPLAY 1.021277 (-4475 5100);
DISPLAY INVISIBLE (-4475 5100);
FORCEPROP 1 LASTPIN (-4525 5000) $PN 1
J 0
(-4515 4980);
DISPLAY 0.489362 (-4515 4980);
FORCEPROP 1 LASTPIN (-4525 4800) $PN 2
J 0
(-4515 4780);
DISPLAY 0.489362 (-4515 4780);
FORCEPROP 1 LAST MATERIAL X6S
J 0
(-4475 4800);
DISPLAY 0.489362 (-4475 4800);
PAINT SKYBLUE (-4475 4800);
FORCEPROP 1 LAST TOLERANCE 20%
J 0
(-4475 4850);
DISPLAY 0.489362 (-4475 4850);
PAINT SKYBLUE (-4475 4850);
FORCEPROP 1 LAST VALUE 22UF
J 0
(-4475 4950);
DISPLAY 0.489362 (-4475 4950);
PAINT SKYBLUE (-4475 4950);
FORCEPROP 1 LAST VOLTAGE 4V
J 0
(-4475 4900);
DISPLAY 0.489362 (-4475 4900);
PAINT SKYBLUE (-4475 4900);
FORCEPROP 1 LAST PACK_TYPE C0402
J 0
(-4475 4700);
DISPLAY 0.489362 (-4475 4700);
PAINT SKYBLUE (-4475 4700);
FORCEPROP 2 LAST CDS_LIB pure_quanta
J 0
(-4525 4900);
PAINT MONO (-4525 4900);
DISPLAY INVISIBLE (-4525 4900);
FORCEPROP 1 LAST PATH I47
J 0
(-4475 5050);
DISPLAY 0.978723 (-4475 5050);
PAINT WHITE (-4475 5050);
DISPLAY INVISIBLE (-4475 5050);
FORCEPROP 1 LAST PART_NUMBER CH622KMEB02
J 0
(-4475 4750);
DISPLAY 0.489362 (-4475 4750);
PAINT SKYBLUE (-4475 4750);
DISPLAY INVISIBLE (-4475 4750);
FORCEADD UNIVERSAL_POWER..1
(-3600 3650);
FORCEPROP 3 LASTPIN (-3600 3600) SIG_NAME PVDD18_S5_P1\g
J 0
(-3590 3610);
DISPLAY 0.659574 (-3590 3610);
PAINT MONO (-3590 3610);
DISPLAY INVISIBLE (-3590 3610);
FORCEPROP 1 LAST HDL_POWER PVDD18_S5_P1
J 1
(-3600 3700);
DISPLAY 0.489362 (-3600 3700);
PAINT GREEN (-3600 3700);
FORCEPROP 2 LAST CDS_LIB pure_quanta_power
J 0
(-3600 3650);
DISPLAY INVISIBLE (-3600 3650);
FORCEPROP 1 LAST PATH I48
J 0
(-3550 3675);
DISPLAY 0.872340 (-3550 3675);
PAINT AQUA (-3550 3675);
DISPLAY INVISIBLE (-3550 3675);
FORCEADD Q_CAP..1
(-3600 3375);
FORCEPROP 1 LAST LOCATION C2292
J 0
(-3550 3475);
DISPLAY 0.489362 (-3550 3475);
PAINT SKYBLUE (-3550 3475);
FORCEPROP 2 LAST $SEC 1
J 0
(-3550 3575);
DISPLAY 0.680851 (-3550 3575);
PAINT MONO (-3550 3575);
DISPLAY INVISIBLE (-3550 3575);
FORCEPROP 2 LAST CDS_SEC 1
J 0
(-3550 3575);
DISPLAY 1.021277 (-3550 3575);
DISPLAY INVISIBLE (-3550 3575);
FORCEPROP 1 LASTPIN (-3600 3475) $PN 1
J 0
(-3590 3455);
DISPLAY 0.489362 (-3590 3455);
FORCEPROP 1 LASTPIN (-3600 3275) $PN 2
J 0
(-3590 3255);
DISPLAY 0.489362 (-3590 3255);
FORCEPROP 1 LAST MATERIAL X6S
J 0
(-3550 3275);
DISPLAY 0.489362 (-3550 3275);
PAINT SKYBLUE (-3550 3275);
FORCEPROP 1 LAST TOLERANCE 20%
J 0
(-3550 3325);
DISPLAY 0.489362 (-3550 3325);
PAINT SKYBLUE (-3550 3325);
FORCEPROP 1 LAST VALUE 22UF
J 0
(-3550 3425);
DISPLAY 0.489362 (-3550 3425);
PAINT SKYBLUE (-3550 3425);
FORCEPROP 1 LAST VOLTAGE 4V
J 0
(-3550 3375);
DISPLAY 0.489362 (-3550 3375);
PAINT SKYBLUE (-3550 3375);
FORCEPROP 1 LAST PACK_TYPE C0402
J 0
(-3550 3175);
DISPLAY 0.489362 (-3550 3175);
PAINT SKYBLUE (-3550 3175);
FORCEPROP 2 LAST CDS_LIB pure_quanta
J 0
(-3600 3375);
PAINT MONO (-3600 3375);
DISPLAY INVISIBLE (-3600 3375);
FORCEPROP 1 LAST PATH I49
J 0
(-3550 3525);
DISPLAY 0.978723 (-3550 3525);
PAINT WHITE (-3550 3525);
DISPLAY INVISIBLE (-3550 3525);
FORCEPROP 1 LAST PART_NUMBER CH622KMEB02
J 0
(-3550 3225);
DISPLAY 0.489362 (-3550 3225);
PAINT SKYBLUE (-3550 3225);
DISPLAY INVISIBLE (-3550 3225);
FORCEADD Q_CAP..1
(-8525 3375);
FORCEPROP 1 LAST LOCATION C3900
J 0
(-8475 3475);
DISPLAY 0.489362 (-8475 3475);
PAINT SKYBLUE (-8475 3475);
FORCEPROP 2 LAST $SEC 1
J 0
(-8475 3575);
DISPLAY 0.680851 (-8475 3575);
PAINT MONO (-8475 3575);
DISPLAY INVISIBLE (-8475 3575);
FORCEPROP 2 LAST CDS_SEC 1
J 0
(-8475 3575);
DISPLAY 1.021277 (-8475 3575);
DISPLAY INVISIBLE (-8475 3575);
FORCEPROP 1 LASTPIN (-8525 3475) $PN 1
J 0
(-8515 3455);
DISPLAY 0.489362 (-8515 3455);
FORCEPROP 1 LASTPIN (-8525 3275) $PN 2
J 0
(-8515 3255);
DISPLAY 0.489362 (-8515 3255);
FORCEPROP 1 LAST MATERIAL X6S
J 0
(-8475 3275);
DISPLAY 0.489362 (-8475 3275);
PAINT SKYBLUE (-8475 3275);
FORCEPROP 1 LAST TOLERANCE 20%
J 0
(-8475 3325);
DISPLAY 0.489362 (-8475 3325);
PAINT SKYBLUE (-8475 3325);
FORCEPROP 1 LAST VALUE 22UF
J 0
(-8475 3425);
DISPLAY 0.489362 (-8475 3425);
PAINT SKYBLUE (-8475 3425);
FORCEPROP 1 LAST VOLTAGE 4V
J 0
(-8475 3375);
DISPLAY 0.489362 (-8475 3375);
PAINT SKYBLUE (-8475 3375);
FORCEPROP 1 LAST PACK_TYPE C0402
J 0
(-8475 3175);
DISPLAY 0.489362 (-8475 3175);
PAINT SKYBLUE (-8475 3175);
FORCEPROP 2 LAST CDS_LIB pure_quanta
J 0
(-8525 3375);
PAINT MONO (-8525 3375);
DISPLAY INVISIBLE (-8525 3375);
FORCEPROP 1 LAST PATH I5
J 0
(-8475 3525);
DISPLAY 0.978723 (-8475 3525);
PAINT WHITE (-8475 3525);
DISPLAY INVISIBLE (-8475 3525);
FORCEPROP 1 LAST PART_NUMBER CH622KMEB02
J 0
(-8475 3225);
DISPLAY 0.489362 (-8475 3225);
PAINT SKYBLUE (-8475 3225);
DISPLAY INVISIBLE (-8475 3225);
FORCEADD Q_CAP..1
(-3150 3375);
FORCEPROP 1 LAST LOCATION C2293
J 0
(-3100 3475);
DISPLAY 0.489362 (-3100 3475);
PAINT SKYBLUE (-3100 3475);
FORCEPROP 2 LAST $SEC 1
J 0
(-3100 3575);
DISPLAY 0.680851 (-3100 3575);
PAINT MONO (-3100 3575);
DISPLAY INVISIBLE (-3100 3575);
FORCEPROP 2 LAST CDS_SEC 1
J 0
(-3100 3575);
DISPLAY 1.021277 (-3100 3575);
DISPLAY INVISIBLE (-3100 3575);
FORCEPROP 1 LASTPIN (-3150 3475) $PN 1
J 0
(-3140 3455);
DISPLAY 0.489362 (-3140 3455);
FORCEPROP 1 LASTPIN (-3150 3275) $PN 2
J 0
(-3140 3255);
DISPLAY 0.489362 (-3140 3255);
FORCEPROP 1 LAST MATERIAL X6S
J 0
(-3100 3275);
DISPLAY 0.489362 (-3100 3275);
PAINT SKYBLUE (-3100 3275);
FORCEPROP 1 LAST TOLERANCE 20%
J 0
(-3100 3325);
DISPLAY 0.489362 (-3100 3325);
PAINT SKYBLUE (-3100 3325);
FORCEPROP 1 LAST VALUE 22UF
J 0
(-3100 3425);
DISPLAY 0.489362 (-3100 3425);
PAINT SKYBLUE (-3100 3425);
FORCEPROP 1 LAST VOLTAGE 4V
J 0
(-3100 3375);
DISPLAY 0.489362 (-3100 3375);
PAINT SKYBLUE (-3100 3375);
FORCEPROP 1 LAST PACK_TYPE C0402
J 0
(-3100 3175);
DISPLAY 0.489362 (-3100 3175);
PAINT SKYBLUE (-3100 3175);
FORCEPROP 2 LAST CDS_LIB pure_quanta
J 0
(-3150 3375);
PAINT MONO (-3150 3375);
DISPLAY INVISIBLE (-3150 3375);
FORCEPROP 1 LAST PATH I50
J 0
(-3100 3525);
DISPLAY 0.978723 (-3100 3525);
PAINT WHITE (-3100 3525);
DISPLAY INVISIBLE (-3100 3525);
FORCEPROP 1 LAST PART_NUMBER CH622KMEB02
J 0
(-3100 3225);
DISPLAY 0.489362 (-3100 3225);
PAINT SKYBLUE (-3100 3225);
DISPLAY INVISIBLE (-3100 3225);
FORCEADD UNIVERSAL_GND..1
(-2700 3025);
FORCEPROP 3 LASTPIN (-2700 3075) SIG_NAME GND\g
J 0
(-2690 3085);
DISPLAY 0.659574 (-2690 3085);
PAINT MONO (-2690 3085);
DISPLAY INVISIBLE (-2690 3085);
FORCEPROP 2 LAST CDS_LIB pure_quanta_power
J 0
(-2700 3025);
DISPLAY INVISIBLE (-2700 3025);
FORCEPROP 1 LAST HDL_POWER GND
J 1
(-2675 2950);
DISPLAY 0.872340 (-2675 2950);
PAINT GREEN (-2675 2950);
DISPLAY INVISIBLE (-2675 2950);
FORCEPROP 1 LAST PATH I51
J 0
(-2625 3025);
DISPLAY 0.872340 (-2625 3025);
PAINT AQUA (-2625 3025);
DISPLAY INVISIBLE (-2625 3025);
FORCEADD Q_CAP..1
(-2700 3375);
FORCEPROP 1 LAST LOCATION C3909
J 0
(-2650 3475);
DISPLAY 0.489362 (-2650 3475);
PAINT SKYBLUE (-2650 3475);
FORCEPROP 2 LAST $SEC 1
J 0
(-2650 3575);
DISPLAY 0.680851 (-2650 3575);
PAINT MONO (-2650 3575);
DISPLAY INVISIBLE (-2650 3575);
FORCEPROP 2 LAST CDS_SEC 1
J 0
(-2650 3575);
DISPLAY 1.021277 (-2650 3575);
DISPLAY INVISIBLE (-2650 3575);
FORCEPROP 1 LASTPIN (-2700 3475) $PN 1
J 0
(-2690 3455);
DISPLAY 0.489362 (-2690 3455);
FORCEPROP 1 LASTPIN (-2700 3275) $PN 2
J 0
(-2690 3255);
DISPLAY 0.489362 (-2690 3255);
FORCEPROP 1 LAST MATERIAL X6S
J 0
(-2650 3275);
DISPLAY 0.489362 (-2650 3275);
PAINT SKYBLUE (-2650 3275);
FORCEPROP 1 LAST TOLERANCE 20%
J 0
(-2650 3325);
DISPLAY 0.489362 (-2650 3325);
PAINT SKYBLUE (-2650 3325);
FORCEPROP 1 LAST VALUE 22UF
J 0
(-2650 3425);
DISPLAY 0.489362 (-2650 3425);
PAINT SKYBLUE (-2650 3425);
FORCEPROP 1 LAST VOLTAGE 4V
J 0
(-2650 3375);
DISPLAY 0.489362 (-2650 3375);
PAINT SKYBLUE (-2650 3375);
FORCEPROP 1 LAST PACK_TYPE C0402
J 0
(-2650 3175);
DISPLAY 0.489362 (-2650 3175);
PAINT SKYBLUE (-2650 3175);
FORCEPROP 2 LAST CDS_LIB pure_quanta
J 0
(-2700 3375);
PAINT MONO (-2700 3375);
DISPLAY INVISIBLE (-2700 3375);
FORCEPROP 1 LAST PATH I52
J 0
(-2650 3525);
DISPLAY 0.978723 (-2650 3525);
PAINT WHITE (-2650 3525);
DISPLAY INVISIBLE (-2650 3525);
FORCEPROP 1 LAST PART_NUMBER CH622KMEB02
J 0
(-2650 3225);
DISPLAY 0.489362 (-2650 3225);
PAINT SKYBLUE (-2650 3225);
DISPLAY INVISIBLE (-2650 3225);
FORCEADD Q_CAP..1
(-3600 4975);
FORCEPROP 1 LAST LOCATION C2260
J 0
(-3550 5075);
DISPLAY 0.489362 (-3550 5075);
PAINT SKYBLUE (-3550 5075);
FORCEPROP 2 LAST $SEC 1
J 0
(-3550 5175);
DISPLAY 0.680851 (-3550 5175);
PAINT MONO (-3550 5175);
DISPLAY INVISIBLE (-3550 5175);
FORCEPROP 2 LAST CDS_SEC 1
J 0
(-3550 5175);
DISPLAY 1.021277 (-3550 5175);
DISPLAY INVISIBLE (-3550 5175);
FORCEPROP 1 LASTPIN (-3600 5075) $PN 1
J 0
(-3590 5055);
DISPLAY 0.489362 (-3590 5055);
FORCEPROP 1 LASTPIN (-3600 4875) $PN 2
J 0
(-3590 4855);
DISPLAY 0.489362 (-3590 4855);
FORCEPROP 1 LAST MATERIAL X6S
J 0
(-3550 4875);
DISPLAY 0.489362 (-3550 4875);
PAINT SKYBLUE (-3550 4875);
FORCEPROP 1 LAST TOLERANCE 20%
J 0
(-3550 4925);
DISPLAY 0.489362 (-3550 4925);
PAINT SKYBLUE (-3550 4925);
FORCEPROP 1 LAST VALUE 22UF
J 0
(-3550 5025);
DISPLAY 0.489362 (-3550 5025);
PAINT SKYBLUE (-3550 5025);
FORCEPROP 1 LAST VOLTAGE 4V
J 0
(-3550 4975);
DISPLAY 0.489362 (-3550 4975);
PAINT SKYBLUE (-3550 4975);
FORCEPROP 1 LAST PACK_TYPE C0402
J 0
(-3550 4775);
DISPLAY 0.489362 (-3550 4775);
PAINT SKYBLUE (-3550 4775);
FORCEPROP 2 LAST CDS_LIB pure_quanta
J 0
(-3600 4975);
PAINT MONO (-3600 4975);
DISPLAY INVISIBLE (-3600 4975);
FORCEPROP 1 LAST PATH I53
J 0
(-3550 5125);
DISPLAY 0.978723 (-3550 5125);
PAINT WHITE (-3550 5125);
DISPLAY INVISIBLE (-3550 5125);
FORCEPROP 1 LAST PART_NUMBER CH622KMEB02
J 0
(-3550 4825);
DISPLAY 0.489362 (-3550 4825);
PAINT SKYBLUE (-3550 4825);
DISPLAY INVISIBLE (-3550 4825);
FORCEADD Q_CAP..1
(-3150 4975);
FORCEPROP 1 LAST LOCATION C2265
J 0
(-3100 5075);
DISPLAY 0.489362 (-3100 5075);
PAINT SKYBLUE (-3100 5075);
FORCEPROP 2 LAST $SEC 1
J 0
(-3100 5175);
DISPLAY 0.680851 (-3100 5175);
PAINT MONO (-3100 5175);
DISPLAY INVISIBLE (-3100 5175);
FORCEPROP 2 LAST CDS_SEC 1
J 0
(-3100 5175);
DISPLAY 1.021277 (-3100 5175);
DISPLAY INVISIBLE (-3100 5175);
FORCEPROP 1 LASTPIN (-3150 5075) $PN 1
J 0
(-3140 5055);
DISPLAY 0.489362 (-3140 5055);
FORCEPROP 1 LASTPIN (-3150 4875) $PN 2
J 0
(-3140 4855);
DISPLAY 0.489362 (-3140 4855);
FORCEPROP 1 LAST MATERIAL X6S
J 0
(-3100 4875);
DISPLAY 0.489362 (-3100 4875);
PAINT SKYBLUE (-3100 4875);
FORCEPROP 1 LAST TOLERANCE 20%
J 0
(-3100 4925);
DISPLAY 0.489362 (-3100 4925);
PAINT SKYBLUE (-3100 4925);
FORCEPROP 1 LAST VALUE 22UF
J 0
(-3100 5025);
DISPLAY 0.489362 (-3100 5025);
PAINT SKYBLUE (-3100 5025);
FORCEPROP 1 LAST VOLTAGE 4V
J 0
(-3100 4975);
DISPLAY 0.489362 (-3100 4975);
PAINT SKYBLUE (-3100 4975);
FORCEPROP 1 LAST PACK_TYPE C0402
J 0
(-3100 4775);
DISPLAY 0.489362 (-3100 4775);
PAINT SKYBLUE (-3100 4775);
FORCEPROP 2 LAST CDS_LIB pure_quanta
J 0
(-3150 4975);
PAINT MONO (-3150 4975);
DISPLAY INVISIBLE (-3150 4975);
FORCEPROP 1 LAST PATH I54
J 0
(-3100 5125);
DISPLAY 0.978723 (-3100 5125);
PAINT WHITE (-3100 5125);
DISPLAY INVISIBLE (-3100 5125);
FORCEPROP 1 LAST PART_NUMBER CH622KMEB02
J 0
(-3100 4825);
DISPLAY 0.489362 (-3100 4825);
PAINT SKYBLUE (-3100 4825);
DISPLAY INVISIBLE (-3100 4825);
FORCEADD UNIVERSAL_POWER..1
(-3600 5250);
FORCEPROP 3 LASTPIN (-3600 5200) SIG_NAME PVDDIO_P1\g
J 0
(-3590 5210);
DISPLAY 0.659574 (-3590 5210);
PAINT MONO (-3590 5210);
DISPLAY INVISIBLE (-3590 5210);
FORCEPROP 1 LAST HDL_POWER PVDDIO_P1
J 1
(-3600 5300);
DISPLAY 0.489362 (-3600 5300);
PAINT GREEN (-3600 5300);
FORCEPROP 2 LAST CDS_LIB pure_quanta_power
J 0
(-3600 5250);
DISPLAY INVISIBLE (-3600 5250);
FORCEPROP 1 LAST PATH I55
J 0
(-3550 5275);
DISPLAY 0.872340 (-3550 5275);
PAINT AQUA (-3550 5275);
DISPLAY INVISIBLE (-3550 5275);
FORCEADD Q_CAP..1
(-2700 4975);
FORCEPROP 1 LAST LOCATION C2270
J 0
(-2650 5075);
DISPLAY 0.489362 (-2650 5075);
PAINT SKYBLUE (-2650 5075);
FORCEPROP 2 LAST $SEC 1
J 0
(-2650 5175);
DISPLAY 0.680851 (-2650 5175);
PAINT MONO (-2650 5175);
DISPLAY INVISIBLE (-2650 5175);
FORCEPROP 2 LAST CDS_SEC 1
J 0
(-2650 5175);
DISPLAY 1.021277 (-2650 5175);
DISPLAY INVISIBLE (-2650 5175);
FORCEPROP 1 LASTPIN (-2700 5075) $PN 1
J 0
(-2690 5055);
DISPLAY 0.489362 (-2690 5055);
FORCEPROP 1 LASTPIN (-2700 4875) $PN 2
J 0
(-2690 4855);
DISPLAY 0.489362 (-2690 4855);
FORCEPROP 1 LAST MATERIAL X6S
J 0
(-2650 4875);
DISPLAY 0.489362 (-2650 4875);
PAINT SKYBLUE (-2650 4875);
FORCEPROP 1 LAST TOLERANCE 20%
J 0
(-2650 4925);
DISPLAY 0.489362 (-2650 4925);
PAINT SKYBLUE (-2650 4925);
FORCEPROP 1 LAST VALUE 22UF
J 0
(-2650 5025);
DISPLAY 0.489362 (-2650 5025);
PAINT SKYBLUE (-2650 5025);
FORCEPROP 1 LAST VOLTAGE 4V
J 0
(-2650 4975);
DISPLAY 0.489362 (-2650 4975);
PAINT SKYBLUE (-2650 4975);
FORCEPROP 1 LAST PACK_TYPE C0402
J 0
(-2650 4775);
DISPLAY 0.489362 (-2650 4775);
PAINT SKYBLUE (-2650 4775);
FORCEPROP 2 LAST CDS_LIB pure_quanta
J 0
(-2700 4975);
PAINT MONO (-2700 4975);
DISPLAY INVISIBLE (-2700 4975);
FORCEPROP 1 LAST PATH I56
J 0
(-2650 5125);
DISPLAY 0.978723 (-2650 5125);
PAINT WHITE (-2650 5125);
DISPLAY INVISIBLE (-2650 5125);
FORCEPROP 1 LAST PART_NUMBER CH622KMEB02
J 0
(-2650 4825);
DISPLAY 0.489362 (-2650 4825);
PAINT SKYBLUE (-2650 4825);
DISPLAY INVISIBLE (-2650 4825);
FORCEADD Q_CAP..1
(-2250 4975);
FORCEPROP 1 LAST LOCATION C2274
J 0
(-2200 5075);
DISPLAY 0.489362 (-2200 5075);
PAINT SKYBLUE (-2200 5075);
FORCEPROP 2 LAST $SEC 1
J 0
(-2200 5175);
DISPLAY 0.680851 (-2200 5175);
PAINT MONO (-2200 5175);
DISPLAY INVISIBLE (-2200 5175);
FORCEPROP 2 LAST CDS_SEC 1
J 0
(-2200 5175);
DISPLAY 1.021277 (-2200 5175);
DISPLAY INVISIBLE (-2200 5175);
FORCEPROP 1 LASTPIN (-2250 5075) $PN 1
J 0
(-2240 5055);
DISPLAY 0.489362 (-2240 5055);
FORCEPROP 1 LASTPIN (-2250 4875) $PN 2
J 0
(-2240 4855);
DISPLAY 0.489362 (-2240 4855);
FORCEPROP 1 LAST MATERIAL X6S
J 0
(-2200 4875);
DISPLAY 0.489362 (-2200 4875);
PAINT SKYBLUE (-2200 4875);
FORCEPROP 1 LAST TOLERANCE 20%
J 0
(-2200 4925);
DISPLAY 0.489362 (-2200 4925);
PAINT SKYBLUE (-2200 4925);
FORCEPROP 1 LAST VALUE 22UF
J 0
(-2200 5025);
DISPLAY 0.489362 (-2200 5025);
PAINT SKYBLUE (-2200 5025);
FORCEPROP 1 LAST VOLTAGE 4V
J 0
(-2200 4975);
DISPLAY 0.489362 (-2200 4975);
PAINT SKYBLUE (-2200 4975);
FORCEPROP 1 LAST PACK_TYPE C0402
J 0
(-2200 4775);
DISPLAY 0.489362 (-2200 4775);
PAINT SKYBLUE (-2200 4775);
FORCEPROP 2 LAST CDS_LIB pure_quanta
J 0
(-2250 4975);
PAINT MONO (-2250 4975);
DISPLAY INVISIBLE (-2250 4975);
FORCEPROP 1 LAST PATH I57
J 0
(-2200 5125);
DISPLAY 0.978723 (-2200 5125);
PAINT WHITE (-2200 5125);
DISPLAY INVISIBLE (-2200 5125);
FORCEPROP 1 LAST PART_NUMBER CH622KMEB02
J 0
(-2200 4825);
DISPLAY 0.489362 (-2200 4825);
PAINT SKYBLUE (-2200 4825);
DISPLAY INVISIBLE (-2200 4825);
FORCEADD Q_CAP..1
(-1800 4975);
FORCEPROP 1 LAST LOCATION C2278
J 0
(-1750 5075);
DISPLAY 0.489362 (-1750 5075);
PAINT SKYBLUE (-1750 5075);
FORCEPROP 2 LAST $SEC 1
J 0
(-1750 5175);
DISPLAY 0.680851 (-1750 5175);
PAINT MONO (-1750 5175);
DISPLAY INVISIBLE (-1750 5175);
FORCEPROP 2 LAST CDS_SEC 1
J 0
(-1750 5175);
DISPLAY 1.021277 (-1750 5175);
DISPLAY INVISIBLE (-1750 5175);
FORCEPROP 1 LASTPIN (-1800 5075) $PN 1
J 0
(-1790 5055);
DISPLAY 0.489362 (-1790 5055);
FORCEPROP 1 LASTPIN (-1800 4875) $PN 2
J 0
(-1790 4855);
DISPLAY 0.489362 (-1790 4855);
FORCEPROP 1 LAST MATERIAL X6S
J 0
(-1750 4875);
DISPLAY 0.489362 (-1750 4875);
PAINT SKYBLUE (-1750 4875);
FORCEPROP 1 LAST TOLERANCE 20%
J 0
(-1750 4925);
DISPLAY 0.489362 (-1750 4925);
PAINT SKYBLUE (-1750 4925);
FORCEPROP 1 LAST VALUE 22UF
J 0
(-1750 5025);
DISPLAY 0.489362 (-1750 5025);
PAINT SKYBLUE (-1750 5025);
FORCEPROP 1 LAST VOLTAGE 4V
J 0
(-1750 4975);
DISPLAY 0.489362 (-1750 4975);
PAINT SKYBLUE (-1750 4975);
FORCEPROP 1 LAST PACK_TYPE C0402
J 0
(-1750 4775);
DISPLAY 0.489362 (-1750 4775);
PAINT SKYBLUE (-1750 4775);
FORCEPROP 2 LAST CDS_LIB pure_quanta
J 0
(-1800 4975);
PAINT MONO (-1800 4975);
DISPLAY INVISIBLE (-1800 4975);
FORCEPROP 1 LAST PATH I58
J 0
(-1750 5125);
DISPLAY 0.978723 (-1750 5125);
PAINT WHITE (-1750 5125);
DISPLAY INVISIBLE (-1750 5125);
FORCEPROP 1 LAST PART_NUMBER CH622KMEB02
J 0
(-1750 4825);
DISPLAY 0.489362 (-1750 4825);
PAINT SKYBLUE (-1750 4825);
DISPLAY INVISIBLE (-1750 4825);
FORCEADD Q_CAP..1
(-1350 4975);
FORCEPROP 1 LAST LOCATION C3910
J 0
(-1300 5075);
DISPLAY 0.489362 (-1300 5075);
PAINT SKYBLUE (-1300 5075);
FORCEPROP 2 LAST $SEC 1
J 0
(-1300 5175);
DISPLAY 0.680851 (-1300 5175);
PAINT MONO (-1300 5175);
DISPLAY INVISIBLE (-1300 5175);
FORCEPROP 2 LAST CDS_SEC 1
J 0
(-1300 5175);
DISPLAY 1.021277 (-1300 5175);
DISPLAY INVISIBLE (-1300 5175);
FORCEPROP 1 LASTPIN (-1350 5075) $PN 1
J 0
(-1340 5055);
DISPLAY 0.489362 (-1340 5055);
FORCEPROP 1 LASTPIN (-1350 4875) $PN 2
J 0
(-1340 4855);
DISPLAY 0.489362 (-1340 4855);
FORCEPROP 1 LAST MATERIAL X6S
J 0
(-1300 4875);
DISPLAY 0.489362 (-1300 4875);
PAINT SKYBLUE (-1300 4875);
FORCEPROP 1 LAST TOLERANCE 20%
J 0
(-1300 4925);
DISPLAY 0.489362 (-1300 4925);
PAINT SKYBLUE (-1300 4925);
FORCEPROP 1 LAST VALUE 22UF
J 0
(-1300 5025);
DISPLAY 0.489362 (-1300 5025);
PAINT SKYBLUE (-1300 5025);
FORCEPROP 1 LAST VOLTAGE 4V
J 0
(-1300 4975);
DISPLAY 0.489362 (-1300 4975);
PAINT SKYBLUE (-1300 4975);
FORCEPROP 1 LAST PACK_TYPE C0402
J 0
(-1300 4775);
DISPLAY 0.489362 (-1300 4775);
PAINT SKYBLUE (-1300 4775);
FORCEPROP 2 LAST CDS_LIB pure_quanta
J 0
(-1350 4975);
PAINT MONO (-1350 4975);
DISPLAY INVISIBLE (-1350 4975);
FORCEPROP 1 LAST PATH I59
J 0
(-1300 5125);
DISPLAY 0.978723 (-1300 5125);
PAINT WHITE (-1300 5125);
DISPLAY INVISIBLE (-1300 5125);
FORCEPROP 1 LAST PART_NUMBER CH622KMEB02
J 0
(-1300 4825);
DISPLAY 0.489362 (-1300 4825);
PAINT SKYBLUE (-1300 4825);
DISPLAY INVISIBLE (-1300 4825);
FORCEADD UNIVERSAL_POWER..1
(-8525 3650);
FORCEPROP 3 LASTPIN (-8525 3600) SIG_NAME PVDDCR_SOC_P1\g
J 0
(-8515 3610);
DISPLAY 0.659574 (-8515 3610);
PAINT MONO (-8515 3610);
DISPLAY INVISIBLE (-8515 3610);
FORCEPROP 1 LAST HDL_POWER PVDDCR_SOC_P1
J 1
(-8525 3700);
DISPLAY 0.489362 (-8525 3700);
PAINT GREEN (-8525 3700);
FORCEPROP 2 LAST CDS_LIB pure_quanta_power
J 0
(-8525 3650);
DISPLAY INVISIBLE (-8525 3650);
FORCEPROP 1 LAST PATH I6
J 0
(-8475 3675);
DISPLAY 0.872340 (-8475 3675);
PAINT AQUA (-8475 3675);
DISPLAY INVISIBLE (-8475 3675);
FORCEADD UNIVERSAL_GND..1
(-900 4625);
FORCEPROP 3 LASTPIN (-900 4675) SIG_NAME GND\g
J 0
(-890 4685);
DISPLAY 0.659574 (-890 4685);
PAINT MONO (-890 4685);
DISPLAY INVISIBLE (-890 4685);
FORCEPROP 2 LAST CDS_LIB pure_quanta_power
J 0
(-900 4625);
PAINT MONO (-900 4625);
DISPLAY INVISIBLE (-900 4625);
FORCEPROP 1 LAST HDL_POWER GND
J 1
(-875 4550);
DISPLAY 0.872340 (-875 4550);
PAINT GREEN (-875 4550);
DISPLAY INVISIBLE (-875 4550);
FORCEPROP 1 LAST PATH I60
J 0
(-825 4625);
DISPLAY 0.872340 (-825 4625);
PAINT AQUA (-825 4625);
DISPLAY INVISIBLE (-825 4625);
FORCEADD Q_CAP..1
(-900 4975);
FORCEPROP 1 LAST LOCATION C3911
J 0
(-850 5075);
DISPLAY 0.489362 (-850 5075);
PAINT SKYBLUE (-850 5075);
FORCEPROP 2 LAST $SEC 1
J 0
(-850 5175);
DISPLAY 0.680851 (-850 5175);
PAINT MONO (-850 5175);
DISPLAY INVISIBLE (-850 5175);
FORCEPROP 2 LAST CDS_SEC 1
J 0
(-850 5175);
DISPLAY 1.021277 (-850 5175);
DISPLAY INVISIBLE (-850 5175);
FORCEPROP 1 LASTPIN (-900 5075) $PN 1
J 0
(-890 5055);
DISPLAY 0.489362 (-890 5055);
FORCEPROP 1 LASTPIN (-900 4875) $PN 2
J 0
(-890 4855);
DISPLAY 0.489362 (-890 4855);
FORCEPROP 1 LAST MATERIAL X6S
J 0
(-850 4875);
DISPLAY 0.489362 (-850 4875);
PAINT SKYBLUE (-850 4875);
FORCEPROP 1 LAST TOLERANCE 20%
J 0
(-850 4925);
DISPLAY 0.489362 (-850 4925);
PAINT SKYBLUE (-850 4925);
FORCEPROP 1 LAST VALUE 22UF
J 0
(-850 5025);
DISPLAY 0.489362 (-850 5025);
PAINT SKYBLUE (-850 5025);
FORCEPROP 1 LAST VOLTAGE 4V
J 0
(-850 4975);
DISPLAY 0.489362 (-850 4975);
PAINT SKYBLUE (-850 4975);
FORCEPROP 1 LAST PACK_TYPE C0402
J 0
(-850 4775);
DISPLAY 0.489362 (-850 4775);
PAINT SKYBLUE (-850 4775);
FORCEPROP 2 LAST CDS_LIB pure_quanta
J 0
(-900 4975);
PAINT MONO (-900 4975);
DISPLAY INVISIBLE (-900 4975);
FORCEPROP 1 LAST PATH I61
J 0
(-850 5125);
DISPLAY 0.978723 (-850 5125);
PAINT WHITE (-850 5125);
DISPLAY INVISIBLE (-850 5125);
FORCEPROP 1 LAST PART_NUMBER CH622KMEB02
J 0
(-850 4825);
DISPLAY 0.489362 (-850 4825);
PAINT SKYBLUE (-850 4825);
DISPLAY INVISIBLE (-850 4825);
FORCEADD Q_CAP..1
(-6725 4900);
FORCEPROP 1 LAST LOCATION C2276
J 0
(-6675 5000);
DISPLAY 0.489362 (-6675 5000);
PAINT SKYBLUE (-6675 5000);
FORCEPROP 2 LAST $SEC 1
J 0
(-6675 5100);
DISPLAY 0.680851 (-6675 5100);
PAINT MONO (-6675 5100);
DISPLAY INVISIBLE (-6675 5100);
FORCEPROP 2 LAST CDS_SEC 1
J 0
(-6675 5100);
DISPLAY 1.021277 (-6675 5100);
DISPLAY INVISIBLE (-6675 5100);
FORCEPROP 1 LASTPIN (-6725 5000) $PN 1
J 0
(-6715 4980);
DISPLAY 0.489362 (-6715 4980);
FORCEPROP 1 LASTPIN (-6725 4800) $PN 2
J 0
(-6715 4780);
DISPLAY 0.489362 (-6715 4780);
FORCEPROP 1 LAST MATERIAL X6S
J 0
(-6675 4800);
DISPLAY 0.489362 (-6675 4800);
PAINT SKYBLUE (-6675 4800);
FORCEPROP 1 LAST TOLERANCE 20%
J 0
(-6675 4850);
DISPLAY 0.489362 (-6675 4850);
PAINT SKYBLUE (-6675 4850);
FORCEPROP 1 LAST VALUE 22UF
J 0
(-6675 4950);
DISPLAY 0.489362 (-6675 4950);
PAINT SKYBLUE (-6675 4950);
FORCEPROP 1 LAST VOLTAGE 4V
J 0
(-6675 4900);
DISPLAY 0.489362 (-6675 4900);
PAINT SKYBLUE (-6675 4900);
FORCEPROP 1 LAST PACK_TYPE C0402
J 0
(-6675 4700);
DISPLAY 0.489362 (-6675 4700);
PAINT SKYBLUE (-6675 4700);
FORCEPROP 2 LAST CDS_LIB pure_quanta
J 0
(-6725 4900);
PAINT MONO (-6725 4900);
DISPLAY INVISIBLE (-6725 4900);
FORCEPROP 1 LAST PATH I62
J 0
(-6675 5050);
DISPLAY 0.978723 (-6675 5050);
PAINT WHITE (-6675 5050);
DISPLAY INVISIBLE (-6675 5050);
FORCEPROP 1 LAST PART_NUMBER CH622KMEB02
J 0
(-6675 4750);
DISPLAY 0.489362 (-6675 4750);
PAINT SKYBLUE (-6675 4750);
DISPLAY INVISIBLE (-6675 4750);
FORCEADD Q_CAP..1
(-8525 4100);
FORCEPROP 1 LAST LOCATION C2259
J 0
(-8475 4200);
DISPLAY 0.489362 (-8475 4200);
PAINT SKYBLUE (-8475 4200);
FORCEPROP 2 LAST $SEC 1
J 0
(-8475 4300);
DISPLAY 0.680851 (-8475 4300);
PAINT MONO (-8475 4300);
DISPLAY INVISIBLE (-8475 4300);
FORCEPROP 2 LAST CDS_SEC 1
J 0
(-8475 4300);
DISPLAY 1.021277 (-8475 4300);
DISPLAY INVISIBLE (-8475 4300);
FORCEPROP 1 LASTPIN (-8525 4200) $PN 1
J 0
(-8515 4180);
DISPLAY 0.489362 (-8515 4180);
FORCEPROP 1 LASTPIN (-8525 4000) $PN 2
J 0
(-8515 3980);
DISPLAY 0.489362 (-8515 3980);
FORCEPROP 1 LAST MATERIAL X6S
J 0
(-8475 4000);
DISPLAY 0.489362 (-8475 4000);
PAINT SKYBLUE (-8475 4000);
FORCEPROP 1 LAST TOLERANCE 20%
J 0
(-8475 4050);
DISPLAY 0.489362 (-8475 4050);
PAINT SKYBLUE (-8475 4050);
FORCEPROP 1 LAST VALUE 22UF
J 0
(-8475 4150);
DISPLAY 0.489362 (-8475 4150);
PAINT SKYBLUE (-8475 4150);
FORCEPROP 1 LAST VOLTAGE 4V
J 0
(-8475 4100);
DISPLAY 0.489362 (-8475 4100);
PAINT SKYBLUE (-8475 4100);
FORCEPROP 1 LAST PACK_TYPE C0402
J 0
(-8475 3900);
DISPLAY 0.489362 (-8475 3900);
PAINT SKYBLUE (-8475 3900);
FORCEPROP 2 LAST CDS_LIB pure_quanta
J 0
(-8525 4100);
PAINT MONO (-8525 4100);
DISPLAY INVISIBLE (-8525 4100);
FORCEPROP 1 LAST PATH I7
J 0
(-8475 4250);
DISPLAY 0.978723 (-8475 4250);
PAINT WHITE (-8475 4250);
DISPLAY INVISIBLE (-8475 4250);
FORCEPROP 1 LAST PART_NUMBER CH622KMEB02
J 0
(-8475 3950);
DISPLAY 0.489362 (-8475 3950);
PAINT SKYBLUE (-8475 3950);
DISPLAY INVISIBLE (-8475 3950);
FORCEADD UNIVERSAL_POWER..1
(-8525 4375);
FORCEPROP 3 LASTPIN (-8525 4325) SIG_NAME PVDDCR_SOC_P1\g
J 0
(-8515 4335);
DISPLAY 0.659574 (-8515 4335);
PAINT MONO (-8515 4335);
DISPLAY INVISIBLE (-8515 4335);
FORCEPROP 1 LAST HDL_POWER PVDDCR_SOC_P1
J 1
(-8525 4425);
DISPLAY 0.489362 (-8525 4425);
PAINT GREEN (-8525 4425);
FORCEPROP 2 LAST CDS_LIB pure_quanta_power
J 0
(-8525 4375);
DISPLAY INVISIBLE (-8525 4375);
FORCEPROP 1 LAST PATH I8
J 0
(-8475 4400);
DISPLAY 0.872340 (-8475 4400);
PAINT AQUA (-8475 4400);
DISPLAY INVISIBLE (-8475 4400);
FORCEADD Q_CAP..1
(-8525 4900);
FORCEPROP 1 LAST LOCATION C2258
J 0
(-8475 5000);
DISPLAY 0.489362 (-8475 5000);
PAINT SKYBLUE (-8475 5000);
FORCEPROP 2 LAST $SEC 1
J 0
(-8475 5100);
DISPLAY 0.680851 (-8475 5100);
PAINT MONO (-8475 5100);
DISPLAY INVISIBLE (-8475 5100);
FORCEPROP 2 LAST CDS_SEC 1
J 0
(-8475 5100);
DISPLAY 1.021277 (-8475 5100);
DISPLAY INVISIBLE (-8475 5100);
FORCEPROP 1 LASTPIN (-8525 5000) $PN 1
J 0
(-8515 4980);
DISPLAY 0.489362 (-8515 4980);
FORCEPROP 1 LASTPIN (-8525 4800) $PN 2
J 0
(-8515 4780);
DISPLAY 0.489362 (-8515 4780);
FORCEPROP 1 LAST MATERIAL X6S
J 0
(-8475 4800);
DISPLAY 0.489362 (-8475 4800);
PAINT SKYBLUE (-8475 4800);
FORCEPROP 1 LAST TOLERANCE 20%
J 0
(-8475 4850);
DISPLAY 0.489362 (-8475 4850);
PAINT SKYBLUE (-8475 4850);
FORCEPROP 1 LAST VALUE 22UF
J 0
(-8475 4950);
DISPLAY 0.489362 (-8475 4950);
PAINT SKYBLUE (-8475 4950);
FORCEPROP 1 LAST VOLTAGE 4V
J 0
(-8475 4900);
DISPLAY 0.489362 (-8475 4900);
PAINT SKYBLUE (-8475 4900);
FORCEPROP 1 LAST PACK_TYPE C0402
J 0
(-8475 4700);
DISPLAY 0.489362 (-8475 4700);
PAINT SKYBLUE (-8475 4700);
FORCEPROP 2 LAST CDS_LIB pure_quanta
J 0
(-8525 4900);
PAINT MONO (-8525 4900);
DISPLAY INVISIBLE (-8525 4900);
FORCEPROP 1 LAST PATH I9
J 0
(-8475 5050);
DISPLAY 0.978723 (-8475 5050);
PAINT WHITE (-8475 5050);
DISPLAY INVISIBLE (-8475 5050);
FORCEPROP 1 LAST PART_NUMBER CH622KMEB02
J 0
(-8475 4750);
DISPLAY 0.489362 (-8475 4750);
PAINT SKYBLUE (-8475 4750);
DISPLAY INVISIBLE (-8475 4750);
FORCEADD QUANTA_TITLE_BLOCK_C..1
(225 -500);
FORCEPROP 0 LAST CDS_CON_LAST_MODIFIED Thu Sep 14 16:12:03 2023
J 0
(-1660 -485);
DISPLAY INVISIBLE (-1660 -485);
FORCEPROP 1 LAST CUSTOM_TXT_CDS <CON_LAST_MODIFIED>
J 0
(-1660 -485);
DISPLAY 0.978723 (-1660 -485);
FORCEPROP 2 LAST CUSTOM_TXT_CDS <XR_PAGE_TITLE>
J 0
(-7665 4750);
DISPLAY 0.638298 (-7665 4750);
PAINT PINK (-7665 4750);
DISPLAY INVISIBLE (-7665 4750);
FORCEPROP 1 LAST CUSTOM_TXT_CDS <NAME_2>
J 0
(-2950 -450);
FORCEPROP 1 LAST CUSTOM_TXT_CDS <NAME_1>
J 0
(-2950 -325);
FORCEPROP 1 LAST CUSTOM_TXT_CDS <Q_NUMBER>
J 0
(-1178 -397);
DISPLAY 1.212766 (-1178 -397);
FORCEPROP 1 LAST CUSTOM_TXT_CDS <Q_PROJ>
J 0
(-2157 -398);
DISPLAY 1.212766 (-2157 -398);
FORCEPROP 1 LAST CUSTOM_TXT_CDS <Q_REV>
J 0
(41 -397);
DISPLAY 1.212766 (41 -397);
FORCEPROP 1 LAST CUSTOM_TXT_CDS <CON_PAGE_NUM> OF <CON_TOTAL_PAGES>
J 0
(-221 -482);
DISPLAY 0.978723 (-221 -482);
FORCEPROP 1 LAST Q_TITLE CPU1 CAVITY TOP DECOUPLING CAPS
J 0
(-9141 -474);
DISPLAY 2.446809 (-9141 -474);
PAINT GREEN (-9141 -474);
FORCEPROP 2 LAST CDS_LIB pure_quanta
J 0
(225 -500);
DISPLAY INVISIBLE (225 -500);
FORCEPROP 1 LAST CDS_LMAN_SYM_OUTLINE -9475,6775,100,-125
J 0
(225 -500);
DISPLAY 0.468085 (225 -500);
PAINT GREEN (225 -500);
DISPLAY INVISIBLE (225 -500);
FORCEPROP 2 LAST PAGE_BORDER TRUE
J 0
(-7665 4750);
DISPLAY 0.638298 (-7665 4750);
PAINT PINK (-7665 4750);
DISPLAY INVISIBLE (-7665 4750);
FORCEPROP 2 LAST CDS_XR_PAGE_TITLE CR-72 : @T6G_MB_LIB.T6G(SCH_1):PAGE72
J 0
(-7665 4750);
DISPLAY 0.638298 (-7665 4750);
PAINT PINK (-7665 4750);
DISPLAY INVISIBLE (-7665 4750);
FORCEPROP 1 LAST Q_DEPT BU9
J 1
(-3538 -451);
DISPLAY 1.957447 (-3538 -451);
PAINT GREEN (-3538 -451);
DISPLAY INVISIBLE (-3538 -451);
FORCEPROP 1 LAST COMMENT_BODY TRUE
J 0
(237 -513);
DISPLAY 0.978723 (237 -513);
PAINT GREEN (237 -513);
DISPLAY INVISIBLE (237 -513);
WIRE 16 -1 (-7175 5075)(-7625 5075);
WIRE 16 -1 (-6725 5075)(-7175 5075);
WIRE 16 -1 (-7175 5000)(-7175 5075);
WIRE 16 -1 (-7625 5075)(-7625 5000);
WIRE 16 -1 (-7625 5075)(-8075 5075);
WIRE 16 -1 (-8075 5000)(-8075 5075);
WIRE 16 -1 (-8075 5075)(-8525 5075);
WIRE 16 -1 (-6275 5075)(-6725 5075);
WIRE 16 -1 (-6725 5000)(-6725 5075);
WIRE 16 -1 (-5825 5075)(-6275 5075);
WIRE 16 -1 (-6275 5075)(-6275 5000);
WIRE 16 -1 (-8525 5075)(-8525 5125);
WIRE 16 -1 (-8525 5075)(-8525 5000);
WIRE 16 -1 (-5375 5075)(-5825 5075);
WIRE 16 -1 (-5825 5000)(-5825 5075);
WIRE 16 -1 (-4925 5075)(-5375 5075);
WIRE 16 -1 (-5375 5000)(-5375 5075);
WIRE 16 -1 (-4525 5075)(-4925 5075);
WIRE 16 -1 (-4925 5075)(-4925 5000);
WIRE 16 -1 (-4525 5000)(-4525 5075);
WIRE 16 -1 (-7625 4675)(-8075 4675);
WIRE 16 -1 (-7175 4675)(-7625 4675);
WIRE 16 -1 (-7625 4675)(-7625 4800);
WIRE 16 -1 (-8075 4675)(-8075 4800);
WIRE 16 -1 (-8075 4675)(-8525 4675);
WIRE 16 -1 (-8525 4675)(-8525 4800);
WIRE 16 -1 (-6725 4675)(-7175 4675);
WIRE 16 -1 (-7175 4675)(-7175 4800);
WIRE 16 -1 (-6275 4675)(-6725 4675);
WIRE 16 -1 (-6725 4675)(-6725 4800);
WIRE 16 -1 (-5825 4675)(-6275 4675);
WIRE 16 -1 (-6275 4675)(-6275 4800);
WIRE 16 -1 (-5375 4675)(-5825 4675);
WIRE 16 -1 (-5825 4675)(-5825 4800);
WIRE 16 -1 (-4925 4675)(-5375 4675);
WIRE 16 -1 (-5375 4675)(-5375 4800);
WIRE 16 -1 (-4525 4675)(-4925 4675);
WIRE 16 -1 (-4925 4675)(-4925 4800);
WIRE 16 -1 (-4525 4675)(-4525 4800);
WIRE 16 -1 (-4525 4575)(-4525 4675);
WIRE 16 -1 (-7175 4275)(-7625 4275);
WIRE 16 -1 (-6725 4275)(-7175 4275);
WIRE 16 -1 (-7175 4200)(-7175 4275);
WIRE 16 -1 (-7625 4275)(-7625 4200);
WIRE 16 -1 (-7625 4275)(-8075 4275);
WIRE 16 -1 (-8075 4200)(-8075 4275);
WIRE 16 -1 (-8075 4275)(-8525 4275);
WIRE 16 -1 (-6275 4275)(-6725 4275);
WIRE 16 -1 (-6725 4200)(-6725 4275);
WIRE 16 -1 (-5825 4275)(-6275 4275);
WIRE 16 -1 (-6275 4275)(-6275 4200);
WIRE 16 -1 (-8525 4275)(-8525 4325);
WIRE 16 -1 (-8525 4275)(-8525 4200);
WIRE 16 -1 (-5375 4275)(-5825 4275);
WIRE 16 -1 (-5825 4200)(-5825 4275);
WIRE 16 -1 (-4925 4275)(-5375 4275);
WIRE 16 -1 (-5375 4200)(-5375 4275);
WIRE 16 -1 (-4525 4275)(-4925 4275);
WIRE 16 -1 (-4925 4275)(-4925 4200);
WIRE 16 -1 (-4525 4200)(-4525 4275);
WIRE 16 -1 (-7625 3875)(-8075 3875);
WIRE 16 -1 (-7175 3875)(-7625 3875);
WIRE 16 -1 (-7625 3875)(-7625 4000);
WIRE 16 -1 (-8075 3875)(-8075 4000);
WIRE 16 -1 (-8075 3875)(-8525 3875);
WIRE 16 -1 (-8525 3875)(-8525 4000);
WIRE 16 -1 (-6725 3875)(-7175 3875);
WIRE 16 -1 (-7175 3875)(-7175 4000);
WIRE 16 -1 (-6275 3875)(-6725 3875);
WIRE 16 -1 (-6725 3875)(-6725 4000);
WIRE 16 -1 (-5825 3875)(-6275 3875);
WIRE 16 -1 (-6275 3875)(-6275 4000);
WIRE 16 -1 (-5375 3875)(-5825 3875);
WIRE 16 -1 (-5825 3875)(-5825 4000);
WIRE 16 -1 (-4925 3875)(-5375 3875);
WIRE 16 -1 (-5375 3875)(-5375 4000);
WIRE 16 -1 (-4525 3875)(-4925 3875);
WIRE 16 -1 (-4925 3875)(-4925 4000);
WIRE 16 -1 (-4525 3875)(-4525 4000);
WIRE 16 -1 (-4525 3775)(-4525 3875);
WIRE 16 -1 (-7150 1750)(-7600 1750);
WIRE 16 -1 (-6700 1750)(-7150 1750);
WIRE 16 -1 (-7150 1675)(-7150 1750);
WIRE 16 -1 (-7600 1750)(-7600 1675);
WIRE 16 -1 (-7600 1750)(-8050 1750);
WIRE 16 -1 (-8050 1675)(-8050 1750);
WIRE 16 -1 (-8050 1750)(-8500 1750);
WIRE 16 -1 (-6250 1750)(-6700 1750);
WIRE 16 -1 (-6700 1675)(-6700 1750);
WIRE 16 -1 (-5800 1750)(-6250 1750);
WIRE 16 -1 (-6250 1750)(-6250 1675);
WIRE 16 -1 (-8500 1750)(-8500 1800);
WIRE 16 -1 (-8500 1750)(-8500 1675);
WIRE 16 -1 (-5350 1750)(-5800 1750);
WIRE 16 -1 (-5800 1675)(-5800 1750);
WIRE 16 -1 (-4900 1750)(-5350 1750);
WIRE 16 -1 (-5350 1675)(-5350 1750);
WIRE 16 -1 (-4500 1750)(-4900 1750);
WIRE 16 -1 (-4900 1750)(-4900 1675);
WIRE 16 -1 (-4500 1675)(-4500 1750);
WIRE 16 -1 (-7600 1350)(-8050 1350);
WIRE 16 -1 (-7150 1350)(-7600 1350);
WIRE 16 -1 (-7600 1350)(-7600 1475);
WIRE 16 -1 (-8050 1350)(-8050 1475);
WIRE 16 -1 (-8050 1350)(-8500 1350);
WIRE 16 -1 (-8500 1350)(-8500 1475);
WIRE 16 -1 (-6700 1350)(-7150 1350);
WIRE 16 -1 (-7150 1350)(-7150 1475);
WIRE 16 -1 (-6250 1350)(-6700 1350);
WIRE 16 -1 (-6700 1350)(-6700 1475);
WIRE 16 -1 (-5800 1350)(-6250 1350);
WIRE 16 -1 (-6250 1350)(-6250 1475);
WIRE 16 -1 (-5350 1350)(-5800 1350);
WIRE 16 -1 (-5800 1350)(-5800 1475);
WIRE 16 -1 (-4900 1350)(-5350 1350);
WIRE 16 -1 (-5350 1350)(-5350 1475);
WIRE 16 -1 (-4500 1350)(-4900 1350);
WIRE 16 -1 (-4900 1350)(-4900 1475);
WIRE 16 -1 (-4500 1350)(-4500 1475);
WIRE 16 -1 (-4500 1250)(-4500 1350);
WIRE 16 -1 (-7150 1000)(-7600 1000);
WIRE 16 -1 (-6700 1000)(-7150 1000);
WIRE 16 -1 (-7150 925)(-7150 1000);
WIRE 16 -1 (-7600 925)(-7600 1000);
WIRE 16 -1 (-7600 1000)(-8050 1000);
WIRE 16 -1 (-8050 925)(-8050 1000);
WIRE 16 -1 (-8050 1000)(-8500 1000);
WIRE 16 -1 (-6250 1000)(-6700 1000);
WIRE 16 -1 (-6700 1000)(-6700 925);
WIRE 16 -1 (-6250 925)(-6250 1000);
WIRE 16 -1 (-8500 1000)(-8500 1050);
WIRE 16 -1 (-8500 1000)(-8500 925);
WIRE 16 -1 (-7600 600)(-8050 600);
WIRE 16 -1 (-7150 600)(-7600 600);
WIRE 16 -1 (-7600 600)(-7600 725);
WIRE 16 -1 (-8050 600)(-8050 725);
WIRE 16 -1 (-8050 600)(-8500 600);
WIRE 16 -1 (-8500 600)(-8500 725);
WIRE 16 -1 (-6700 600)(-7150 600);
WIRE 16 -1 (-7150 600)(-7150 725);
WIRE 16 -1 (-6250 600)(-6700 600);
WIRE 16 -1 (-6700 600)(-6700 725);
WIRE 16 -1 (-6250 600)(-6250 725);
WIRE 16 -1 (-6250 500)(-6250 600);
WIRE 16 -1 (-8075 3475)(-8075 3550);
WIRE 16 -1 (-8075 3550)(-8525 3550);
WIRE 16 -1 (-8525 3550)(-8525 3600);
WIRE 16 -1 (-8525 3550)(-8525 3475);
WIRE 16 -1 (-8075 3275)(-8075 3150);
WIRE 16 -1 (-8075 3075)(-8075 3150);
WIRE 16 -1 (-8075 3150)(-8525 3150);
WIRE 16 -1 (-8525 3150)(-8525 3275);
WIRE 16 3135 (-8775 2175)(-4100 2175);
WIRE 16 3135 (-8775 400)(-8775 2175);
WIRE 16 3135 (-4100 400)(-4100 2175);
WIRE 16 3135 (-8775 400)(-4100 400);
WIRE 16 3135 (-8775 5675)(-4025 5675);
WIRE 16 3135 (-8775 2700)(-8775 5675);
WIRE 16 3135 (-4025 2700)(-4025 5675);
WIRE 16 3135 (-8775 2700)(-4025 2700);
WIRE 16 -1 (-2700 3475)(-2700 3550);
WIRE 16 -1 (-2700 3550)(-3150 3550);
WIRE 16 -1 (-3150 3475)(-3150 3550);
WIRE 16 -1 (-3150 3550)(-3600 3550);
WIRE 16 -1 (-3600 3550)(-3600 3600);
WIRE 16 -1 (-3600 3550)(-3600 3475);
WIRE 16 -1 (-2700 3150)(-3150 3150);
WIRE 16 -1 (-2700 3275)(-2700 3150);
WIRE 16 -1 (-2700 3075)(-2700 3150);
WIRE 16 -1 (-3150 3275)(-3150 3150);
WIRE 16 -1 (-3150 3150)(-3600 3150);
WIRE 16 -1 (-3600 3150)(-3600 3275);
WIRE 16 3135 (-50 2900)(-50 4175);
WIRE 16 3135 (-3900 2900)(-50 2900);
WIRE 16 3135 (-3900 4175)(-50 4175);
WIRE 16 3135 (-3900 2900)(-3900 4175);
WIRE 16 -1 (-2700 4750)(-3150 4750);
WIRE 16 -1 (-2250 4750)(-2700 4750);
WIRE 16 -1 (-2700 4750)(-2700 4875);
WIRE 16 -1 (-3150 4750)(-3150 4875);
WIRE 16 -1 (-3150 4750)(-3600 4750);
WIRE 16 -1 (-3600 4750)(-3600 4875);
WIRE 16 -1 (-1800 4750)(-2250 4750);
WIRE 16 -1 (-2250 4750)(-2250 4875);
WIRE 16 -1 (-1350 4750)(-1800 4750);
WIRE 16 -1 (-1800 4750)(-1800 4875);
WIRE 16 -1 (-900 4750)(-1350 4750);
WIRE 16 -1 (-1350 4750)(-1350 4875);
WIRE 16 -1 (-900 4750)(-900 4875);
WIRE 16 -1 (-900 4675)(-900 4750);
WIRE 16 -1 (-3150 5075)(-3150 5150);
WIRE 16 -1 (-2700 5150)(-3150 5150);
WIRE 16 -1 (-3150 5150)(-3600 5150);
WIRE 16 -1 (-3600 5150)(-3600 5200);
WIRE 16 -1 (-3600 5150)(-3600 5075);
WIRE 16 -1 (-2250 5150)(-2700 5150);
WIRE 16 -1 (-2700 5150)(-2700 5075);
WIRE 16 -1 (-1800 5150)(-2250 5150);
WIRE 16 -1 (-2250 5075)(-2250 5150);
WIRE 16 -1 (-1350 5150)(-1800 5150);
WIRE 16 -1 (-1800 5075)(-1800 5150);
WIRE 16 -1 (-900 5150)(-1350 5150);
WIRE 16 -1 (-1350 5075)(-1350 5150);
WIRE 16 -1 (-900 5075)(-900 5150);
WIRE 16 3135 (-3875 5700)(-75 5700);
WIRE 16 3135 (-3875 4500)(-3875 5700);
WIRE 16 3135 (-75 4500)(-75 5700);
WIRE 16 3135 (-3875 4500)(-75 4500);
DOT 1 (-1800 5150);
DOT 1 (-8500 1000);
DOT 1 (-8500 1750);
DOT 1 (-8525 3550);
DOT 1 (-8525 4275);
DOT 1 (-8525 5075);
DOT 1 (-8050 600);
DOT 1 (-7600 600);
DOT 1 (-8050 1000);
DOT 1 (-8050 1350);
DOT 1 (-8050 1750);
DOT 1 (-7600 1000);
DOT 1 (-7600 1350);
DOT 1 (-7600 1750);
DOT 1 (-7150 600);
DOT 1 (-6700 600);
DOT 1 (-6250 600);
DOT 1 (-7150 1000);
DOT 1 (-7150 1350);
DOT 1 (-6700 1000);
DOT 1 (-6700 1350);
DOT 1 (-7150 1750);
DOT 1 (-6700 1750);
DOT 1 (-6250 1350);
DOT 1 (-6250 1750);
DOT 1 (-8075 3150);
DOT 1 (-8075 3875);
DOT 1 (-7625 3875);
DOT 1 (-7175 3875);
DOT 1 (-6725 3875);
DOT 1 (-6275 3875);
DOT 1 (-5800 1350);
DOT 1 (-5800 1750);
DOT 1 (-5350 1350);
DOT 1 (-5350 1750);
DOT 1 (-4900 1350);
DOT 1 (-4900 1750);
DOT 1 (-4500 1350);
DOT 1 (-5825 3875);
DOT 1 (-5375 3875);
DOT 1 (-4925 3875);
DOT 1 (-4525 3875);
DOT 1 (-8075 4275);
DOT 1 (-8075 4675);
DOT 1 (-7625 4275);
DOT 1 (-7625 4675);
DOT 1 (-8075 5075);
DOT 1 (-7625 5075);
DOT 1 (-7175 4275);
DOT 1 (-6725 4275);
DOT 1 (-7175 4675);
DOT 1 (-6725 4675);
DOT 1 (-6275 4275);
DOT 1 (-6275 4675);
DOT 1 (-7175 5075);
DOT 1 (-6725 5075);
DOT 1 (-6275 5075);
DOT 1 (-5825 4275);
DOT 1 (-5825 4675);
DOT 1 (-5375 4275);
DOT 1 (-5375 4675);
DOT 1 (-5825 5075);
DOT 1 (-5375 5075);
DOT 1 (-4925 4275);
DOT 1 (-4925 4675);
DOT 1 (-4525 4675);
DOT 1 (-4925 5075);
DOT 1 (-3600 3550);
DOT 1 (-3150 3150);
DOT 1 (-3150 3550);
DOT 1 (-2700 3150);
DOT 1 (-3150 4750);
DOT 1 (-3600 5150);
DOT 1 (-3150 5150);
DOT 1 (-2700 4750);
DOT 1 (-2250 4750);
DOT 1 (-2700 5150);
DOT 1 (-2250 5150);
DOT 1 (-1800 4750);
DOT 1 (-1350 4750);
DOT 1 (-1350 5150);
DOT 1 (-900 4750);
FORCENOTE
PVDD11_S3_P1: 16PCS 22UF ON TOP
(-8525 2000) 0;
DISPLAY LEFT (-8525 2000);
DISPLAY 2.510638 (-8525 2000);
PAINT WHITE (-8525 2000);
FORCENOTE
PVDDCR_SOC_P1: 22PCS 22UF ON TOP
(-8525 5375) 0;
DISPLAY LEFT (-8525 5375);
DISPLAY 2.510638 (-8525 5375);
PAINT WHITE (-8525 5375);
FORCENOTE
5
(-6725 1075) 0;
DISPLAY LEFT (-6725 1075);
DISPLAY 1.021277 (-6725 1075);
PAINT SKYBLUE (-6725 1075);
FORCENOTE
5
(-6725 1850) 0;
DISPLAY LEFT (-6725 1850);
DISPLAY 1.021277 (-6725 1850);
PAINT SKYBLUE (-6725 1850);
FORCENOTE
10
(-4550 1850) 0;
DISPLAY LEFT (-4550 1850);
DISPLAY 1.021277 (-4550 1850);
PAINT SKYBLUE (-4550 1850);
FORCENOTE
5
(-6750 4375) 0;
DISPLAY LEFT (-6750 4375);
DISPLAY 1.021277 (-6750 4375);
PAINT SKYBLUE (-6750 4375);
FORCENOTE
5
(-6750 5175) 0;
DISPLAY LEFT (-6750 5175);
DISPLAY 1.021277 (-6750 5175);
PAINT SKYBLUE (-6750 5175);
FORCENOTE
10
(-4575 4325) 0;
DISPLAY LEFT (-4575 4325);
DISPLAY 1.021277 (-4575 4325);
PAINT SKYBLUE (-4575 4325);
FORCENOTE
10
(-4575 5175) 0;
DISPLAY LEFT (-4575 5175);
DISPLAY 1.021277 (-4575 5175);
PAINT SKYBLUE (-4575 5175);
FORCENOTE
PVDD18_S5_P1: 3PCS 22UF ON TOP
(-3675 3850) 0;
DISPLAY LEFT (-3675 3850);
DISPLAY 2.510638 (-3675 3850);
PAINT WHITE (-3675 3850);
FORCENOTE
5
(-1825 5250) 0;
DISPLAY LEFT (-1825 5250);
DISPLAY 1.021277 (-1825 5250);
PAINT SKYBLUE (-1825 5250);
FORCENOTE
PVDDIO_P1: 7PCS 22UF ON TOP
(-3625 5475) 0;
DISPLAY LEFT (-3625 5475);
DISPLAY 2.510638 (-3625 5475);
PAINT WHITE (-3625 5475);
QUIT
